G04 ================== begin FILE IDENTIFICATION RECORD ==================*
G04 Layout Name:  DAT6MTH3AD0_t6m_cm_d_brd_103112_274.brd*
G04 Film Name:    in1*
G04 File Format:  Gerber RS274X*
G04 File Origin:  Cadence Allegro 16.3-S048*
G04 Origin Date:  Tue Nov 26 10:18:25 2013*
G04 *
G04 Layer:  VIA CLASS/IN1*
G04 Layer:  PIN/IN1*
G04 Layer:  MANUFACTURING/PHOTOPLOT_OUTLINE*
G04 Layer:  ETCH/IN1*
G04 Layer:  DRAWING FORMAT/TITLE_BLOCK*
G04 Layer:  DRAWING FORMAT/TITLE_DATA_IN1*
G04 *
G04 Offset:    (0.00 0.00)*
G04 Mirror:    No*
G04 Mode:      Positive*
G04 Rotation:  0*
G04 FullContactRelief:  No*
G04 UndefLineWidth:     6.00*
G04 ================== end FILE IDENTIFICATION RECORD ====================*
%FSLAX25Y25*MOIN*%
%IR0*IPPOS*OFA0.00000B0.00000*MIA0B0*SFA1.00000B1.00000*%
%ADD11C,.02*%
%ADD12C,.06*%
%ADD14C,.061*%
%ADD15C,.058*%
%ADD13C,.0193*%
%ADD10C,.077*%
%ADD16C,.01*%
%ADD17C,.04*%
%ADD18C,.015*%
%ADD19C,.018*%
%ADD20C,.004*%
%ADD21C,.005*%
%ADD22C,.0041*%
%ADD23C,.006*%
%ADD24C,.008*%
%ADD25C,.009*%
%ADD26C,.0045*%
%ADD27C,.0039*%
%ADD30C,.03004*%
%ADD37C,.03006*%
%ADD36C,.06204*%
%ADD35C,.07104*%
%ADD31C,.02804*%
%ADD32C,.02734*%
%ADD34C,.07604*%
%ADD33C,.02934*%
%ADD28C,.08704*%
%ADD38C,.15004*%
%ADD29C,.15206*%
G75*
%LPD*%
G75*
G36*
G01X49628Y313035D02*
X13930D01*
X8450Y318515D01*
Y376383D01*
X10830Y378763D01*
X25700D01*
X42950Y361513D01*
Y356469D01*
X52190Y347229D01*
Y315597D01*
X49628Y313035D01*
G37*
G36*
G01X121109Y573778D02*
G03Y571246I-809J-1266D01*
G02X122647Y570404I538J-843D01*
G01Y526885D01*
X119707Y523945D01*
X86148D01*
X83997Y526096D01*
Y560976D01*
X84803Y561782D01*
X85007Y561784D01*
G03X86492Y563269I-17J1502D01*
G01X86494Y563473D01*
X92616Y569595D01*
Y647018D01*
X97910Y652312D01*
X121106D01*
X122647Y650771D01*
Y574620D01*
G02X121109Y573778I-1000J1D01*
G37*
G36*
G01X130711Y85830D02*
X133191D01*
X133380Y85641D01*
Y79501D01*
X132124Y78245D01*
X123381D01*
X122620Y79006D01*
Y84980D01*
X123470Y85830D01*
X128449D01*
X128591Y85706D01*
G03X130569I989J1131D01*
G01X130711Y85830D01*
G37*
G36*
G01X129990Y396594D02*
Y406790D01*
Y411080D01*
X130355Y411445D01*
X152007D01*
X152894Y410558D01*
Y409155D01*
Y400310D01*
X147700Y395116D01*
X131468D01*
X129990Y396594D01*
G37*
G36*
G01X131246Y452015D02*
X141442D01*
X145728Y447729D01*
Y432134D01*
Y429327D01*
X144840Y428439D01*
X142033D01*
X128142D01*
X127403Y429178D01*
Y451270D01*
X128148Y452015D01*
X131246D01*
G37*
G36*
G01X148210Y249033D02*
G03I-640J0D01*
G37*
G36*
G01X216898Y298413D02*
X219894Y295416D01*
X220300D01*
G02X220800Y294916I0J-500D01*
G01Y291392D01*
X220737Y291279D01*
G03Y289817I1312J-731D01*
G01X220800Y289704D01*
Y289004D01*
X218534Y286738D01*
X215078D01*
G02X214087Y287602I0J1000D01*
G03X213766Y288344I-1488J-203D01*
G02Y289602I777J629D01*
G03X213785Y289625I-1149J968D01*
G02X214568Y289620I390J-314D01*
G03X214803Y291715I1181J928D01*
G02X213545I-629J777D01*
G03X213522Y291734I-968J-1149D01*
G02X213527Y292517I314J390D01*
G03X211432Y292752I-928J1181D01*
G02Y291494I-777J-629D01*
G03X211413Y291471I1149J-968D01*
G02X210631Y291476I-389J314D01*
G03X209600Y292042I-1181J-929D01*
G02X208700Y293037I100J995D01*
G01Y296812D01*
X204434Y301078D01*
X203556D01*
X203447Y301134D01*
G03X202525Y301360I-924J-1776D01*
G01X200470D01*
X200188Y301078D01*
X197271D01*
G02X196272Y302117I0J1000D01*
G03X193641Y303166I-1501J59D01*
G02X192937Y303119I-376J330D01*
G03X191011Y303160I-988J-1132D01*
G02X189756Y303164I-625J781D01*
G03X187309Y302046I-946J-1166D01*
G02X186309Y301078I-1000J32D01*
G01X186306D01*
G02X185806Y301578I0J500D01*
G01Y301757D01*
X185918Y301894D01*
G03X183530Y303713I-1164J949D01*
G02X182398Y303344I-815J580D01*
G03X181021Y303122I-477J-1424D01*
G02X179821I-600J800D01*
G03X178021I-900J-1202D01*
G02X176821I-600J800D01*
G03X174422Y302015I-900J-1202D01*
G02X173424Y301078I-998J63D01*
G01X164476D01*
G02X163559Y302476I0J1000D01*
G03X160803I-1378J599D01*
G02X159886Y301078I-917J-398D01*
G01X151270D01*
X145080Y294888D01*
Y291509D01*
X143806Y290235D01*
X140415D01*
G02X139420Y291136I0J1000D01*
G03X137922Y292489I-1495J-149D01*
G02X136920Y293489I-2J1000D01*
G01Y294234D01*
G02X137948Y295234I1000J0D01*
G03Y298236I42J1501D01*
G02X136920Y299236I-28J1000D01*
G01Y300007D01*
X137157Y300287D01*
X137338Y300317D01*
G03Y303281I-247J1482D01*
G01X137157Y303311D01*
X136920Y303591D01*
Y304220D01*
X137013Y304419D01*
X137098Y304491D01*
G03Y306789I-968J1149D01*
G01X137097Y306790D01*
G02X136920Y307172I323J382D01*
G01Y310158D01*
X138650Y311888D01*
Y393614D01*
G02X139150Y394114I500J0D01*
G01X148115D01*
X153896Y399895D01*
Y410973D01*
X152422Y412446D01*
X147230D01*
G02X146730Y412946I0J500D01*
G01Y440016D01*
G02X147230Y440516I500J0D01*
G01X147312D01*
G03X147766Y443430I508J1413D01*
G02X146730Y444429I-36J999D01*
G01Y448144D01*
X146435Y448438D01*
G02X146288Y448792I353J354D01*
G01Y451508D01*
X147290Y452510D01*
X157936D01*
X158730Y451716D01*
Y438162D01*
X158612Y438043D01*
Y408782D01*
X158690Y408703D01*
Y403533D01*
X163510Y398713D01*
Y388877D01*
X160006Y385373D01*
X159951Y385340D01*
G03X159414Y384803I759J-1296D01*
G01X159381Y384747D01*
X159254Y384620D01*
Y384417D01*
X159240Y384352D01*
X159234Y384320D01*
G03Y383768I1476J-276D01*
G01X159240Y383736D01*
X159254Y383671D01*
Y377337D01*
G02X159080Y376958I-500J0D01*
G03Y374678I978J-1140D01*
G02X159254Y374299I-326J-379D01*
G01Y372849D01*
X159630D01*
X176137Y356342D01*
G02X176238Y355780I-354J-354D01*
G03X176518Y354118I1366J-624D01*
G02X176547Y353460I-362J-346D01*
G03X179000Y351736I1173J-938D01*
G02X180559Y351920I852J-523D01*
G01X186181Y346298D01*
G02X186246Y344954I-707J-708D01*
G03X188360Y342840I1158J-956D01*
G02X189704Y342775I636J-772D01*
G01X190735Y341744D01*
G02X190859Y341241I-353J-354D01*
G03X191143Y339826I1434J-448D01*
G01X191260Y339687D01*
Y338486D01*
X191127Y338342D01*
G03Y336302I1103J-1020D01*
G01X191260Y336158D01*
Y335034D01*
X191165Y334832D01*
X191079Y334761D01*
G03Y332451I961J-1155D01*
G01X191165Y332380D01*
X191260Y332178D01*
Y328185D01*
G02X190379Y327192I-1000J0D01*
G03X190970Y324257I177J-1491D01*
G01X191037Y324276D01*
X191423D01*
X195583Y320116D01*
X199506D01*
X199603Y320073D01*
G03X200819I608J1373D01*
G01X200916Y320116D01*
X204030D01*
X204970Y319176D01*
Y318864D01*
X205158Y318676D01*
X211158D01*
G03X214042I1442J424D01*
G01X215120D01*
X220531Y313265D01*
X220603Y313024D01*
X220575Y312885D01*
X220570Y312859D01*
G03X220752Y311841I1479J-261D01*
G01X220820Y311724D01*
Y311193D01*
G02X220511Y310731I-500J0D01*
G01X220245Y310621D01*
G02X219765Y310675I-191J462D01*
G03X217732Y308502I-866J-1227D01*
G02Y307244I-777J-629D01*
G03X219860Y305144I1167J-946D01*
G01X220126Y305174D01*
X220511Y305015D01*
G02X220820Y304553I-191J-462D01*
G01Y304022D01*
X220752Y303905D01*
G03X220737Y302417I1297J-757D01*
G01X220800Y302304D01*
Y302070D01*
G02X220300Y301570I-500J0D01*
G01X220147D01*
X220020Y301656D01*
G03X216898Y299998I-1121J-1658D01*
G01Y298413D01*
G37*
G36*
G01X180978Y634587D02*
G03X183982I1502J-2D01*
G01Y634588D01*
G02X184482Y635088I500J0D01*
G01X195320D01*
X199098Y631310D01*
G02X199186Y629996I-707J-707D01*
G03X200302Y627585I1194J-911D01*
G02X201250Y626586I-52J-999D01*
G01Y624832D01*
X201190Y624720D01*
G03Y623290I1320J-715D01*
G01X201250Y623178D01*
Y621352D01*
G02X200065Y620369I-1000J0D01*
G03X199408Y617439I-279J-1476D01*
G01X199539Y617405D01*
X200112Y616832D01*
Y590343D01*
X199758Y589988D01*
G02X198127Y590311I-707J707D01*
G03X196164Y588348I-1387J-576D01*
G02X196487Y586717I-384J-924D01*
G01X195938Y586169D01*
Y584945D01*
G02X195438Y584445I-500J0D01*
G01X179251D01*
G02X178896Y584593I0J500D01*
G03X176764I-1066J-1058D01*
G02X176409Y584445I-355J352D01*
G01X174214D01*
G02X173768Y584718I0J500D01*
G03X171092I-1338J-683D01*
G02X170646Y584445I-446J227D01*
G01X168262D01*
G02X167839Y584678I0J500D01*
G03X165736Y585123I-1269J-804D01*
G02X165105Y585186I-277J416D01*
G01X162196Y588095D01*
X162164Y588236D01*
G03X161031Y589369I-1465J-332D01*
G01X160890Y589401D01*
X154612Y595679D01*
X154589Y596059D01*
X154707Y596208D01*
G03X154523Y598263I-1180J930D01*
G02X154473Y598962I331J375D01*
G03X153210Y601432I-1144J973D01*
G02X152130Y602429I-80J997D01*
G01Y608484D01*
G02X153363Y609456I1000J0D01*
G03Y612378I349J1461D01*
G02X152130Y613350I-233J972D01*
G01Y618398D01*
G02X153460Y619342I1000J0D01*
G03Y622178I495J1418D01*
G02X152130Y623122I-330J944D01*
G01Y633248D01*
X153970Y635088D01*
X155486D01*
G02X156476Y633947I0J-1000D01*
G03X159450I1487J-212D01*
G02X160440Y635088I990J141D01*
G01X161858D01*
X161951Y635049D01*
G03X163109I579J1386D01*
G01X163202Y635088D01*
X168224D01*
X168478Y634916D01*
X168535Y634773D01*
G03X171325I1395J556D01*
G01X171382Y634916D01*
X171636Y635088D01*
X180478D01*
G02X180978Y634588I0J-500D01*
G01Y634587D01*
G37*
G36*
G01X184230Y660136D02*
G02X184730Y659636I0J-500D01*
G01Y647224D01*
G02X184230Y646724I-500J0D01*
G01X158710D01*
G02X158210Y647224I0J500D01*
G01Y659636D01*
G02X158710Y660136I500J0D01*
G01X184230D01*
G37*
G36*
G01X193800Y7579D02*
Y18076D01*
X194810Y19086D01*
X203596D01*
X206292Y21782D01*
Y26175D01*
X208130Y28013D01*
X210631D01*
X210746Y28128D01*
X235036D01*
X238570Y31662D01*
Y50165D01*
G03X238595Y50206I-1270J802D01*
G01X239880D01*
X240082Y50111D01*
X240153Y50025D01*
G03X242467I1157J958D01*
G01X242538Y50111D01*
X242740Y50206D01*
X243801D01*
X244016Y50095D01*
X244086Y49996D01*
G03X246534I1224J871D01*
G01X246604Y50095D01*
X246819Y50206D01*
X247787D01*
X248003Y50094D01*
X248074Y49995D01*
G03X250526I1226J867D01*
G01X250597Y50094D01*
X250813Y50206D01*
X256964D01*
X257017Y50259D01*
X258549D01*
X261718Y53428D01*
X281766D01*
X282570Y52624D01*
Y31949D01*
X281880Y31259D01*
X276630D01*
G02X276130Y31759I0J500D01*
G01Y41830D01*
X273780Y44180D01*
X262233D01*
X255920Y37867D01*
Y30000D01*
X255882Y29908D01*
G03Y28760I1388J-574D01*
G01X255920Y28668D01*
Y10181D01*
X252818Y7079D01*
X194300D01*
G02X193800Y7579I0J500D01*
G37*
G36*
G01X333044Y465842D02*
X331284Y459824D01*
Y452518D01*
X332894Y450908D01*
Y450138D01*
X332600Y449845D01*
Y447632D01*
X330146Y445178D01*
X325136D01*
X322240Y448075D01*
X320300D01*
X320295Y448080D01*
X309932D01*
X309927Y448075D01*
X307476D01*
X293516Y434115D01*
X293104D01*
X293020Y434199D01*
Y434149D01*
X292728Y433857D01*
X268090D01*
X247070Y412837D01*
X243310D01*
X231069Y400596D01*
X225585D01*
G02X224586Y401638I0J1000D01*
G03X221584I-1501J64D01*
G02X220585Y400596I-999J-42D01*
G01X216731D01*
X216172Y401156D01*
X215120D01*
G03X214079Y400736I1J-1502D01*
G02X213732Y400596I-347J360D01*
G01X207740D01*
X206600Y399456D01*
Y371369D01*
X212870Y365099D01*
G02X212900Y363716I-707J-707D01*
G03X214327Y361233I1107J-1015D01*
G02X215540Y360256I213J-977D01*
G01Y358704D01*
G02X214587Y357705I-1000J0D01*
G03X213601Y355137I70J-1500D01*
G02X213693Y353819I-703J-711D01*
G03X214679Y351422I1195J-910D01*
G02X215540Y350431I-139J-990D01*
G01Y340548D01*
X215633Y340455D01*
X215697Y340174D01*
X215649Y340038D01*
G03X215966Y338520I1418J-496D01*
G02X215991Y337187I-733J-680D01*
G03X215927Y335307I1138J-980D01*
G02Y334107I-800J-600D01*
G03X218331I1202J-900D01*
G02Y335307I800J600D01*
G03X218514Y335625I-1201J903D01*
G02X220143Y335945I922J-387D01*
G01X221548Y334540D01*
G02X221623Y333929I-353J-353D01*
G03X223685Y331867I1288J-774D01*
G01X223832Y331956D01*
X224173Y331915D01*
X225897Y330191D01*
Y315348D01*
X225158Y314609D01*
X222941D01*
X216920Y320630D01*
X206865D01*
X201651Y325844D01*
G02Y326552I353J354D01*
G03X199527Y328676I-1061J1063D01*
G02X198819I-354J353D01*
G01X198486Y329009D01*
Y331715D01*
G02X200053Y332539I1000J0D01*
G03X202265Y334414I852J1237D01*
G02X202411Y335021I453J212D01*
G03X202713Y337077I-922J1186D01*
G02Y338237I815J580D01*
G03X200265I-1224J870D01*
G02Y337077I-815J-580D01*
G03X200129Y335569I1224J-871D01*
G02X199983Y334962I-453J-212D01*
G03X199465Y334204I922J-1186D01*
G02X198486Y334346I-479J143D01*
G01Y343665D01*
X198551Y343779D01*
G03Y345257I-1308J739D01*
G01X198486Y345371D01*
Y351135D01*
G02X198986Y351635I500J0D01*
G03Y354639I1J1502D01*
G02X198486Y355139I0J500D01*
G01Y362923D01*
X192260Y369149D01*
Y375554D01*
G02X192740Y376053I500J-1D01*
G03Y379055I-59J1501D01*
G02X192260Y379554I20J500D01*
G01Y380903D01*
G02X193392Y381894I1000J0D01*
G03Y384872I198J1489D01*
G02X192260Y385863I-132J991D01*
G01Y387961D01*
G02X193648Y388883I1000J0D01*
G03Y391651I583J1384D01*
G02X192260Y392573I-388J922D01*
G01Y394163D01*
G02X193688Y395067I1000J0D01*
G03Y397783I642J1358D01*
G02X192260Y398687I-428J904D01*
G01Y400961D01*
G02X192739Y401460I500J0D01*
G03X193811Y401977I-63J1501D01*
G02X195249Y402054I756J-655D01*
G03X195138Y404136I1024J1099D01*
G02X193700Y404059I-756J655D01*
G03X192739Y404462I-1025J-1098D01*
G02X192260Y404961I21J499D01*
G01Y406487D01*
X200866Y415093D01*
X226418D01*
X226534Y415209D01*
G02X227829Y415310I707J-707D01*
G03X229928Y417409I884J1215D01*
G02X230029Y418704I808J588D01*
G01X242915Y431590D01*
G02X243500Y431679I353J-354D01*
G03X245527Y433706I696J1331D01*
G01X245451Y433852D01*
X245500Y434175D01*
X256010Y444685D01*
Y446315D01*
X261300Y451605D01*
X290752D01*
X290824Y451534D01*
X294530Y455240D01*
X298377D01*
X301455Y458318D01*
G03X301582Y461010I-1415J1416D01*
G02X301645Y462355I770J638D01*
G01X306059Y466769D01*
G02X306759Y466776I354J-353D01*
G03X309111Y467126I1041J1083D01*
G01X309145Y467186D01*
X313280Y471322D01*
G02X314784Y471220I708J-707D01*
G03X316358Y473582I1196J908D01*
G01X316227Y473616D01*
X315856Y473986D01*
Y476333D01*
G02X316896Y477332I1000J0D01*
G03Y480334I60J1501D01*
G02X315856Y481333I-40J999D01*
G01Y484417D01*
X315933Y484601D01*
X315936Y484604D01*
Y512151D01*
X316018Y512233D01*
Y528610D01*
X315550Y529078D01*
Y549156D01*
X317750Y551356D01*
Y568526D01*
X317860Y568663D01*
G03X318174Y569387I-1173J939D01*
G01X318198Y569551D01*
X322160Y573513D01*
X334242D01*
X340833Y566922D01*
X340889Y566614D01*
X340850Y566528D01*
G03X343012Y564590I1340J-680D01*
G01X343108Y564648D01*
X344940Y562815D01*
Y543658D01*
G02X344440Y543158I-500J0D01*
G01X341208D01*
X341079Y543233D01*
X341046Y543250D01*
G03Y540612I-716J-1319D01*
G01X341079Y540629D01*
X341208Y540704D01*
X344440D01*
G02X344940Y540204I0J-500D01*
G01Y524680D01*
X350292Y519328D01*
G02X350027Y517724I-707J-707D01*
G03X349800Y515166I663J-1348D01*
G02X349885Y513625I-593J-806D01*
G03X352164Y511706I1017J-1105D01*
G02X353712Y511871I841J-542D01*
G01X355070Y510513D01*
Y498616D01*
X343288Y486834D01*
X337829D01*
X333044Y482049D01*
Y465842D01*
G37*
G36*
G01X228879Y460381D02*
X228270D01*
G02X227772Y460837I0J500D01*
G03X224780I-1496J-133D01*
G02X224282Y460381I-498J44D01*
G01X223769D01*
X212011Y472139D01*
Y486359D01*
G02X213072Y487357I1000J0D01*
G03X213800Y487472I137J1496D01*
G03X214127Y487664I-591J1381D01*
G02X215291I582J-813D01*
G03X217574Y489480I918J1189D01*
G02X218423Y490874I919J396D01*
G01X218965D01*
X220178Y492087D01*
X222225D01*
X222710Y491661D01*
X222747Y491506D01*
G03X225671I1462J347D01*
G01X225708Y491661D01*
X226193Y492087D01*
X228106D01*
X235926Y499907D01*
Y502845D01*
X232598Y506173D01*
Y509813D01*
X233359Y510574D01*
X233624D01*
G03X234405Y510797I4J1467D01*
G01X234527Y510873D01*
X235481D01*
G02X235834Y510019I0J-500D01*
G01X235815Y510000D01*
X235803Y509990D01*
G03X235496Y509608I974J-1097D01*
G03X235365Y508489I1280J-717D01*
G03X235523Y508128I1411J402D01*
G03X235602Y508011I1254J761D01*
G03X238212Y509193I1174J880D01*
G03X237886Y509851I-1436J-302D01*
G02X237767Y510885I789J615D01*
G03X238187Y512608I-991J1154D01*
G01X238168Y512655D01*
X238103Y512794D01*
Y512906D01*
G02X238603Y513406I500J0D01*
G01X238607D01*
X242822Y517621D01*
Y538083D01*
X242466Y538439D01*
X240775D01*
X240659Y538506D01*
G03X239976Y538702I-734J-1270D01*
G01X239779Y538709D01*
X238249Y540239D01*
X238242Y540436D01*
G03X238233Y540556I-1466J-50D01*
G03X238212Y540690I-1458J-160D01*
G01X238201Y540741D01*
Y543179D01*
X238212Y543231D01*
G03Y543841I-1436J305D01*
G01X238201Y543893D01*
Y545051D01*
X224698Y558554D01*
Y560481D01*
X224789Y560610D01*
G03Y562340I-1228J865D01*
G01X224698Y562469D01*
Y564508D01*
G02X224757Y564846I1000J0D01*
G01X224698Y564905D01*
Y574392D01*
X234360Y584054D01*
X247041D01*
G02X248040Y583095I0J-1000D01*
G03X250972Y582699I1501J61D01*
G01X251022Y582855D01*
X251285Y583048D01*
X257288D01*
G02X258210Y581870I-63J-999D01*
G03X261146I1468J-317D01*
G02X262068Y583048I985J179D01*
G01X262742D01*
X264816Y580974D01*
X265134Y580656D01*
X281699D01*
G02X282198Y580180I-1J-500D01*
G03X284915Y579373I1500J73D01*
G02X286413Y579514I811J-585D01*
G01X287915Y578012D01*
X300500D01*
X303256Y575256D01*
Y573756D01*
X303169Y573628D01*
G03Y571936I1241J-846D01*
G01X303256Y571808D01*
Y516208D01*
G02X301956Y515254I-1000J0D01*
G03Y512420I-499J-1417D01*
G02X303256Y511466I300J-954D01*
G01Y491114D01*
X302999Y490682D01*
X302899Y490618D01*
G03X302544Y490301I810J-1265D01*
G02X301920Y490176I-388J316D01*
G03X301838Y487489I-711J-1323D01*
G02X303256Y486581I418J-908D01*
G01Y478338D01*
X292800Y467882D01*
X292418Y467861D01*
X292268Y467981D01*
G03X290407Y467998I-941J-1170D01*
G02X288904Y468333I-613J791D01*
G03X288769Y468549I-1336J-685D01*
G02Y469749I800J600D01*
G03X287122Y472084I-1202J900D01*
G02X285829Y472957I-297J955D01*
G03X284777Y471399I-1497J-123D01*
G02X286070Y470526I297J-955D01*
G03X286365Y469749I1497J124D01*
G02Y468549I-800J-600D01*
G03X288487Y466462I1203J-900D01*
G02X289990Y466127I613J-791D01*
G03X290157Y465871I1334J688D01*
G01Y465870D01*
X290277Y465720D01*
X290256Y465338D01*
X287464Y462546D01*
X281159D01*
G02X280292Y464044I0J1000D01*
G03X280456Y465119I-1302J749D01*
G01X280432Y465228D01*
X280479Y465442D01*
X280772Y465827D01*
X280907Y465878D01*
G03X278914Y466958I-527J1406D01*
G01X278938Y466849D01*
X278891Y466635D01*
X278598Y466250D01*
X278463Y466199D01*
G03X277688Y464044I527J-1406D01*
G02X276821Y462546I-867J-498D01*
G01X264546D01*
X264445Y462593D01*
G03X263169I-638J-1359D01*
G01X263068Y462546D01*
X260112D01*
X260092Y462526D01*
G02X258659Y462546I-707J707D01*
G03X256068Y461434I-1091J-1033D01*
G02X255069Y460381I-999J-53D01*
G01X253782D01*
X253292Y460871D01*
X253273Y461046D01*
G03X250287I-1493J-163D01*
G01X250268Y460871D01*
X249778Y460381D01*
X245384D01*
X244916Y460727D01*
X244863Y460858D01*
G03X242079I-1392J-566D01*
G01X242026Y460727D01*
X241557Y460381D01*
X240357D01*
X239885Y460738D01*
X239834Y460872D01*
G03X237026I-1404J-534D01*
G01X236975Y460738D01*
X236503Y460381D01*
X233883D01*
G02X232883Y461394I0J1000D01*
G03X232843Y461758I-1502J19D01*
G02X232863Y462052I487J115D01*
G03X229999Y462247I-1402J539D01*
G02X229979Y461953I-487J-115D01*
G03X229879Y461394I1402J-539D01*
G02X228879Y460381I-1000J-13D01*
G37*
G36*
G01X247127Y51208D02*
G02X246673Y51498I0J500D01*
G03X243947I-1363J-631D01*
G02X243493Y51207I-454J209D01*
G01X243021D01*
X242766Y51382D01*
X242710Y51527D01*
G03X241453Y52478I-1400J-544D01*
G01X241275Y52495D01*
X240920Y52850D01*
Y57573D01*
X242050Y58703D01*
X250955D01*
X251002Y58656D01*
X258804D01*
X259220Y58241D01*
Y56022D01*
X259200Y56002D01*
Y52782D01*
X257678Y51260D01*
X256602D01*
X256549Y51208D01*
X250968D01*
X250723Y51363D01*
X250661Y51496D01*
G03X247939I-1361J-634D01*
G02X247485Y51208I-453J212D01*
G01X247127D01*
G37*
G36*
G01X239423Y324039D02*
X239150Y324312D01*
G02X239333Y325870I707J707D01*
G03X239243Y328479I-788J1279D01*
G03X238621Y328649I-698J-1330D01*
G02X238146Y329148I25J500D01*
G01Y331149D01*
G02X238622Y331649I500J0D01*
G03X239961Y332640I-74J1500D01*
G01X240011Y332777D01*
X240475Y333136D01*
X240638Y333140D01*
G03X241582Y335777I-40J1502D01*
G02X241424Y337114I655J755D01*
G03X241033Y339272I-1206J896D01*
G01X240934Y339336D01*
X240725Y339689D01*
X240699Y339897D01*
X240729Y339997D01*
G03X239225Y341929I-1439J431D01*
G02X238182Y342896I-43J999D01*
G01Y344923D01*
X238123Y344982D01*
Y346061D01*
X233229Y350955D01*
Y351959D01*
X233711Y352449D01*
X233883Y352470D01*
G03X235179Y353714I-186J1491D01*
G03X234844Y354931I-1482J247D01*
G02X234812Y356149I777J630D01*
G03X233706Y358582I-1177J933D01*
G02X233229Y359082I23J500D01*
G01Y365158D01*
X233574Y365626D01*
X233704Y365679D01*
G03Y368461I-568J1391D01*
G01X233574Y368514D01*
X233229Y368982D01*
Y385414D01*
X234562Y386746D01*
G02X235269I354J-353D01*
G01X235279Y386736D01*
X235289Y386725D01*
G03X235350Y386660I1125J995D01*
G02X235419Y386039I-354J-354D01*
G03X235570Y384230I1268J-805D01*
G03X236218Y383807I1117J1004D01*
G03X238165Y385500I469J1427D01*
G02X239150Y386676I984J176D01*
G01X241151D01*
X241546Y387072D01*
X247106D01*
G02X247606Y386572I0J-500D01*
G01Y383188D01*
X247605Y383187D01*
Y358334D01*
G02X246479Y357342I-1000J0D01*
G03Y354368I-214J-1487D01*
G02X247605Y353376I126J-992D01*
G01Y343544D01*
G02X246248Y342610I-1000J0D01*
G03X245005Y342551I-557J-1395D01*
G03X245109Y339830I686J-1336D01*
G02X245522Y338308I-387J-922D01*
G03X246667Y335855I1163J-951D01*
G01X246682D01*
G02X247182Y335355I0J-500D01*
G01Y335167D01*
X247181Y334978D01*
X246822Y334505D01*
X246687Y334454D01*
G03X246372Y334290I531J-1405D01*
G03X245779Y332618I846J-1241D01*
G01X245819Y332485D01*
X245752Y332219D01*
X245304Y331771D01*
Y329454D01*
X245712Y329046D01*
Y327697D01*
G02X245425Y327245I-500J0D01*
G01X245408Y327237D01*
X245406Y327236D01*
G03X244245Y325420I841J-1817D01*
G01X244246D01*
Y324580D01*
X243705Y324039D01*
X239423D01*
G37*
G36*
G01X259194Y385788D02*
G02X260181Y384950I0J-1000D01*
G03X262550Y383981I1482J243D01*
G02X263239Y383886I295J-404D01*
G03X263534Y386024I1182J926D01*
G02X262845Y386119I-295J404D01*
G03X262768Y386210I-1184J-924D01*
G02X262738Y386849I369J338D01*
G03X262626Y388792I-1199J906D01*
G02X262488Y389137I362J345D01*
G01Y393945D01*
X262901Y394358D01*
X276398D01*
X281374Y389383D01*
X281399Y389349D01*
X281425Y389314D01*
X281439Y389296D01*
G03X281698Y389037I1183J924D01*
G01X281716Y389023D01*
X281751Y388997D01*
X281785Y388972D01*
X282223Y388534D01*
G02X281876Y387680I-353J-354D01*
G01X281866D01*
G03X281175Y384843I-2J-1502D01*
G03X282963Y385154I689J1335D01*
G02X284091Y385390I731J-682D01*
G03X284502Y385278I596J1379D01*
G03X284785Y385270I184J1491D01*
G03X284887Y385280I-95J1499D01*
G03X284983Y385296I-199J1489D01*
G03X285081Y385320I-308J1470D01*
G02X285566Y385191I131J-483D01*
G01X293090Y377667D01*
X293105D01*
G02X294017Y376258I0J-1000D01*
G03X293931Y376010I1371J-614D01*
G02X293006Y375893I-485J121D01*
G03X291802Y376675I-1321J-716D01*
G03X290192Y375336I-116J-1498D01*
G03X290184Y375168I1494J-155D01*
G03X292932Y374338I1502J9D01*
G02X294397Y374515I813J-582D01*
G03X294441Y374478I988J1131D01*
G03X295206Y374153I947J1166D01*
G03X295806Y374201I183J1491D01*
G02X296930Y373773I278J-960D01*
G03X298036Y373079I1272J799D01*
G03X298057Y373077I153J1494D01*
G03X298208Y376074I145J1495D01*
G03X297784Y376015I-7J-1502D01*
G02X296660Y376443I-278J960D01*
G03X296428Y376728I-1272J-799D01*
G01X296360Y376793D01*
X296284Y376958D01*
G02X296738Y377667I454J209D01*
G01X323067D01*
X325846Y374888D01*
Y367590D01*
X325212Y366956D01*
X317344D01*
G02X316351Y367836I0J1000D01*
G03X313393Y367335I-1491J-180D01*
G02X312409Y366153I-984J-182D01*
G01X282339D01*
G02X281344Y367260I0J1000D01*
G03X278382I-1481J253D01*
G02X277387Y366153I-995J-107D01*
G01X267879D01*
X262915Y361189D01*
Y342332D01*
X262709Y342126D01*
X262680Y342104D01*
G03X262120Y340529I896J-1206D01*
G02X261642Y339412I-969J-246D01*
G03X261298Y337060I737J-1309D01*
G02X261245Y335621I-720J-694D01*
G03X261164Y335543I1001J-1120D01*
G03X261018Y333638I1083J-1041D01*
G03X261375Y333279I1228J865D01*
G02X261729Y332208I-607J-795D01*
G03X261716Y332160I1443J-417D01*
G03X261707Y331466I1457J-366D01*
G03X261854Y331075I1466J328D01*
G03X261960Y330908I1318J720D01*
G02X262125Y330475I-826J-563D01*
G02X261772Y329931I-496J-65D01*
G03X261029Y327551I429J-1440D01*
G01X261139Y327414D01*
Y324114D01*
X260992Y323764D01*
X260932Y323699D01*
G03X260804Y323540I1103J-1019D01*
G03X260546Y322878I1231J-861D01*
G03X260594Y322256I1489J-198D01*
G01X260633Y322124D01*
X260565Y321859D01*
X257927Y319221D01*
X245770D01*
X245247Y319744D01*
Y324165D01*
X245248D01*
Y325452D01*
G02X245319Y325793I1000J-30D01*
G02X245711Y326264I928J-374D01*
G02X245831Y326329I535J-845D01*
G01X245837Y326332D01*
X245871Y326348D01*
G02X246631Y326344I375J-928D01*
G03X247159Y326198I658J1350D01*
G03X248603Y328423I131J1496D01*
G03X247182Y329192I-1313J-729D01*
G01X247108Y329189D01*
X246909Y329265D01*
X246567Y329607D01*
X246480Y329695D01*
X246306Y329869D01*
Y330580D01*
G02X247245Y331547I999J-31D01*
G03X248675Y332683I-27J1502D01*
G03X248705Y332837I-1457J364D01*
G03X248712Y332890I-1485J223D01*
G03X248514Y333809I-1494J159D01*
G03X248368Y334016I-1296J-759D01*
G01X248316Y334078D01*
X248183Y334413D01*
Y335357D01*
G03Y335384I-1501J13D01*
G01Y337059D01*
G02X248337Y337420I500J0D01*
G01X248631Y337702D01*
X248779Y337729D01*
G03X249296Y340486I-270J1478D01*
G01X249185Y340554D01*
X249058Y340781D01*
Y341912D01*
G02X250221Y342899I1000J0D01*
G03Y345863I245J1482D01*
G02X249058Y346850I-163J987D01*
G01Y350705D01*
G02X250568Y351565I1000J0D01*
G03Y354149I766J1292D01*
G02X249058Y355009I-510J860D01*
G01Y355083D01*
G02X250607Y355919I1000J0D01*
G03Y358349I884J1215D01*
G02X249058Y359185I-549J836D01*
G01Y382352D01*
G02X250299Y383322I1000J0D01*
G03X250722Y383279I362J1458D01*
G03X251463Y383510I-61J1501D01*
G03X251588Y383598I-801J1271D01*
G03X251789Y383788I-927J1182D01*
G02X252997Y383962I717J-697D01*
G03X253792Y383753I765J1293D01*
G03X254187Y383814I-30J1502D01*
G03X254425Y383907I-426J1440D01*
G03X254662Y384053I-666J1346D01*
G02X255354Y383963I300J-400D01*
G03X258001Y384580I1178J932D01*
G03X258017Y385122I-1469J315D01*
G03X258005Y385190I-1485J-227D01*
G01X257995Y385238D01*
Y385288D01*
G02X258495Y385788I500J0D01*
G01X259194D01*
G37*
G36*
G01X244250Y401691D02*
Y410953D01*
G02X244750Y411453I500J0D01*
G01X249276D01*
X253962Y416139D01*
G02X254436Y416270I353J-354D01*
G03X255968Y416787I361J1458D01*
G02X257567Y416733I779J-627D01*
G03X259091Y419067I1231J861D01*
G02X258578Y420755I194J981D01*
G01X266079Y428256D01*
X297355D01*
X297844Y427768D01*
Y418238D01*
X287850Y408244D01*
X272331D01*
X267405Y407177D01*
X262701D01*
X260002Y404478D01*
X258026D01*
X254739Y401191D01*
X244750D01*
G02X244250Y401691I0J500D01*
G37*
G36*
G01X257465Y591608D02*
X255995Y593078D01*
Y627647D01*
X257633Y629285D01*
X260146D01*
X262045Y631184D01*
Y644033D01*
G02X262545Y644533I500J0D01*
G01X265326D01*
X265459Y644400D01*
X278384D01*
G02X278884Y643900I0J-500D01*
G01Y635250D01*
X281289Y632845D01*
Y593794D01*
X279103Y591608D01*
X257465D01*
G37*
G36*
G01X270665Y689631D02*
G03X270767Y692403I-525J1407D01*
G02X270476Y692857I209J454D01*
G01Y697411D01*
X271746Y698681D01*
G02X272452Y698683I354J-353D01*
G03X274898Y699176I1058J1066D01*
G02X275360Y699485I462J-191D01*
G01X281531D01*
X288560Y692456D01*
G02X288264Y690837I-707J-707D01*
G03X290250Y688851I616J-1370D01*
G02X291869Y689147I912J-411D01*
G01X296280Y684736D01*
X299037D01*
X303852Y679921D01*
X304408D01*
X304642Y679688D01*
X307625D01*
X308440Y678872D01*
Y671174D01*
G02X307940Y670674I-500J0D01*
G01X305607D01*
X303834Y672446D01*
X299924D01*
G02X299063Y673955I0J1000D01*
G03X296339Y675176I-1293J765D01*
G02X294679Y674772I-953J303D01*
G01X294121Y675330D01*
G02Y676037I353J354D01*
G01X294122Y676038D01*
X294123Y676039D01*
G03X291999Y678163I-1055J1069D01*
G01X291998Y678162D01*
X291997Y678161D01*
G02X291290I-353J353D01*
G01X291216Y678235D01*
G02X290531Y679740I169J986D01*
G03X288591Y679170I-1283J781D01*
G01X288721Y679107D01*
X288873Y678864D01*
Y678720D01*
G02X288373Y678220I-500J0D01*
G01X287607D01*
X280352Y685476D01*
Y687309D01*
G03X276348I-2002J0D01*
G01Y685044D01*
G02X275848Y684544I-500J0D01*
G01X274014D01*
X270340Y688219D01*
Y689319D01*
X270518Y689576D01*
X270665Y689631D01*
G37*
G36*
G01X301862Y470885D02*
G03I-602J0D01*
G37*
G36*
G01X314788Y323404D02*
X313175Y325017D01*
Y325389D01*
X313192Y325452D01*
G03X311353Y327291I-1452J387D01*
G01X311290Y327274D01*
X310918D01*
X307990Y330202D01*
Y336459D01*
X308130Y336599D01*
Y336678D01*
X312920Y341468D01*
Y354038D01*
X318490Y359608D01*
X325102D01*
G02X325574Y358610I-518J-856D01*
G03X328542I1484J-234D01*
G02X329014Y359608I990J142D01*
G01X334488D01*
X334489Y359606D01*
X334492D01*
X338480Y355618D01*
X338900D01*
X346304Y348215D01*
G02X346450Y347862I-354J-353D01*
G01Y323904D01*
G02X345950Y323404I-500J0D01*
G01X337661D01*
G02X337308Y324258I0J500D01*
G01X337437Y324386D01*
X337692Y324641D01*
Y326768D01*
G02X338963Y327730I1000J0D01*
G03X340566Y328268I407J1446D01*
G03X340650Y329963I-1196J909D01*
G02X340738Y331096I864J503D01*
G03X339030Y333466I-1138J980D01*
G02X337692Y334407I-338J941D01*
G01Y342201D01*
X336725Y343168D01*
X328435D01*
X327258Y341991D01*
Y324791D01*
X327613Y324436D01*
X327792Y324258D01*
G02X327439Y323404I-353J-354D01*
G01X321924D01*
X321884Y323410D01*
G03X321402I-241J-1482D01*
G01X321362Y323404D01*
X319424D01*
X319384Y323410D01*
G03X318902I-241J-1482D01*
G01X318862Y323404D01*
X316924D01*
X316884Y323410D01*
G03X316402I-241J-1482D01*
G01X316362Y323404D01*
X314788D01*
G37*
G36*
G01X306832Y477139D02*
G03I-602J0D01*
G37*
G36*
G01X328850Y342166D02*
X336310D01*
X336690Y341786D01*
Y325056D01*
X336420Y324786D01*
X328680D01*
X328260Y325206D01*
Y341576D01*
X328850Y342166D01*
G37*
G36*
G01X351520Y684891D02*
X350330Y686081D01*
Y693255D01*
X351610Y694535D01*
X360167D01*
X360389Y694414D01*
X360459Y694308D01*
G03X361670Y693627I1258J820D01*
G02X362629Y692772I-31J-1000D01*
G03X365581Y693317I1486J218D01*
G02X366557Y694535I976J218D01*
G01X368687D01*
X370460Y692762D01*
Y686644D01*
X369694Y685878D01*
G02X368352Y685813I-707J707D01*
G03X366129Y685455I-953J-1161D01*
G02X365443Y685297I-423J267D01*
G03X364954Y685493I-795J-1275D01*
G02X364696Y685635I101J490D01*
G02X364431Y685508I-339J367D01*
G03X364010Y685381I219J-1486D01*
G02X363359Y685594I-212J453D01*
G03X360589Y685262I-1319J-719D01*
G02X360106Y684891I-483J129D01*
G01X351520D01*
G37*
G36*
G01X541070Y201382D02*
X543949Y204261D01*
Y213609D01*
G02X544850Y214604I1000J0D01*
G03Y217596I-150J1496D01*
G02X543949Y218591I99J995D01*
G01Y227053D01*
X545039Y228143D01*
X548818D01*
X556549Y220412D01*
X573979D01*
X574102Y220534D01*
X577968D01*
X578230Y220345D01*
X578281Y220191D01*
G03X581133I1426J471D01*
G01X581184Y220345D01*
X581446Y220534D01*
X581842D01*
G02X582308Y220216I0J-500D01*
G03X585106I1399J546D01*
G01X585162Y220360D01*
X585417Y220534D01*
X585829D01*
X586289Y220213D01*
X586346Y220091D01*
G03X589068I1361J637D01*
G01X589125Y220213D01*
X589585Y220534D01*
X590009D01*
X590426Y220303D01*
X590491Y220213D01*
G03X592981Y220299I1216J882D01*
G01X593050Y220409D01*
X593275Y220534D01*
X593953D01*
X594381Y220279D01*
X594445Y220180D01*
G03X597025Y220274I1262J815D01*
G01X597091Y220395D01*
X597326Y220534D01*
X602565D01*
G02X603065Y220034I0J-500D01*
G01Y168712D01*
X602902Y168347D01*
X602831Y168278D01*
G03Y162042I2965J-3118D01*
G01X602902Y161973D01*
X603065Y161608D01*
Y96453D01*
G02X601789Y95492I-1000J0D01*
G03X599915Y94406I-415J-1444D01*
G03X600966Y92602I1459J-358D01*
G02X601659Y91631I-307J-952D01*
G03X601953Y90639I1499J-95D01*
G03X602713Y90100I1206J895D01*
G01X602870Y90051D01*
X603065Y89787D01*
Y12675D01*
G02X602919Y12322I-500J0D01*
G01X597046Y6450D01*
X369576D01*
X368490Y7536D01*
Y28880D01*
X371550Y31940D01*
X465095D01*
X465585Y31536D01*
X465620Y31363D01*
G03X496584I15482J3165D01*
G01X496619Y31536D01*
X497109Y31940D01*
X501010D01*
X541070Y72000D01*
Y103837D01*
G02X542125Y104836I1000J0D01*
G03X542237Y104831I123J1497D01*
G03X543223Y105190I11J1502D01*
G03X543742Y106490I-975J1143D01*
G02X544736Y107594I994J104D01*
G01X544746D01*
G02X545746Y106590I0J-1000D01*
G03X546148Y105559I1502J-8D01*
G03X548644Y107137I1100J1023D01*
G03X547909Y107931I-1396J-555D01*
G02X547546Y109345I481J877D01*
G03X547806Y110269I-1240J848D01*
G03X547769Y110535I-1500J-73D01*
G02X548742Y111762I973J227D01*
G01X549612D01*
X549730Y111693D01*
G03Y114285I760J1296D01*
G01X549612Y114216D01*
X545351D01*
X544978Y113843D01*
X544899Y113763D01*
G02X544360Y113512I-673J741D01*
G01X543943Y113731D01*
X543877Y113814D01*
G03X543783Y113921I-1174J-937D01*
G03X543685Y114015I-1087J-1036D01*
G03X541940Y114177I-985J-1134D01*
G01X541822Y114108D01*
X541570D01*
G02X541070Y114608I0J500D01*
G01Y201382D01*
G37*
G36*
G01X443401Y445925D02*
X443439Y445821D01*
G03X444334Y444926I1411J516D01*
G01X444438Y444888D01*
X456420Y432906D01*
Y401589D01*
X454370Y399539D01*
X427326D01*
X425097Y401767D01*
X422554Y404310D01*
X401117D01*
G02X400763Y404457I0J500D01*
G01X397139Y408082D01*
X397102Y408162D01*
G03X396374Y408890I-1362J-634D01*
G01X396294Y408927D01*
X394822Y410399D01*
G02X394724Y410969I353J354D01*
G03X392746Y412984I-1354J649D01*
G01X392745D01*
G02X392185Y413085I-207J455D01*
G01X386946Y418324D01*
Y438570D01*
X386559Y438957D01*
X386220Y439297D01*
Y441152D01*
X384326Y443046D01*
Y490264D01*
X384530Y490468D01*
X387328D01*
X387358Y490438D01*
X397359D01*
X402930Y484867D01*
Y461924D01*
X413240Y451614D01*
G02X413386Y451225I-353J-354D01*
G01X413383Y451189D01*
X413381Y451174D01*
G03X416318Y450578I1489J-197D01*
G02X416800Y450946I482J-132D01*
G01X420004D01*
G02X420986Y449755I0J-1000D01*
G03X421611Y448228I1474J-288D01*
G02X421731Y446675I-565J-825D01*
G03X421810Y444417I1029J-1094D01*
G02X421850Y442902I-632J-775D01*
G03X423810Y442954I1010J-1112D01*
G02X423770Y444469I632J775D01*
G03X423609Y446820I-1010J1112D01*
G02X423489Y448373I565J825D01*
G03X423497Y448381I-1058J1066D01*
G02X424860Y448397I690J-724D01*
G03X427022Y448545I1010J1112D01*
G02X428540Y448562I766J-642D01*
G03X431014Y450223I1130J989D01*
G01X430962Y450328D01*
Y450446D01*
G02X431462Y450946I500J0D01*
G01X431974D01*
G02X432474Y450446I0J-500D01*
G01Y450315D01*
X432410Y450201D01*
G03X435194Y449755I1310J-734D01*
G02X436176Y450946I982J191D01*
G01X437916D01*
X438000Y450915D01*
G03X438342Y450833I519J1409D01*
G01X438514Y450812D01*
X440254Y449072D01*
G02X440088Y447523I-707J-708D01*
G03X442357Y445896I812J-1263D01*
G01Y445897D01*
X442391Y446032D01*
X442635Y446276D01*
X443050D01*
X443401Y445925D01*
G37*
G36*
G01X392168Y596498D02*
G03Y599302I-538J1402D01*
G02X391847Y599769I179J467D01*
G01Y600603D01*
X393519Y602275D01*
X417575D01*
X418876Y603576D01*
Y610257D01*
G02X419337Y610756I500J0D01*
G03Y613750I-116J1497D01*
G02X418876Y614249I39J499D01*
G01Y623637D01*
X415810Y626703D01*
X407210D01*
X406934Y626929D01*
X406899Y627105D01*
G03X403953I-1473J-296D01*
G01X403918Y626929D01*
X403642Y626703D01*
X392776D01*
X391847Y627632D01*
Y637478D01*
X393333Y638964D01*
X412448D01*
G02X412818Y638800I0J-500D01*
G03X415042I1112J1010D01*
G02X415412Y638964I370J-336D01*
G01X424124D01*
X426765Y636323D01*
X435868D01*
X438487Y633704D01*
G02X438367Y632188I-707J-707D01*
G03X439850Y629596I883J-1215D01*
G02X441250Y628680I400J-916D01*
G01Y618307D01*
G02X440204Y617308I-1000J0D01*
G03Y614308I-69J-1500D01*
G02X441250Y613309I46J-999D01*
G01Y611030D01*
G02X440166Y610034I-1000J0D01*
G03Y607040I-126J-1497D01*
G02X441250Y606044I84J-996D01*
G01Y589605D01*
X440133Y588488D01*
G02X438663Y588549I-707J707D01*
G03X436153Y586948I-1147J-970D01*
G02X435246Y585528I-907J-420D01*
G01X395118D01*
X391847Y588799D01*
Y596031D01*
G02X392168Y596498I500J0D01*
G37*
G36*
G01X409694Y483084D02*
G03I-640J0D01*
G37*
G36*
G01X412900Y482881D02*
G03I-640J0D01*
G37*
G36*
G01X464531Y181827D02*
G02X465031Y181327I0J-500D01*
G01Y153367D01*
G02X464531Y152867I-500J0D01*
G01X444531D01*
G02X444031Y153367I0J500D01*
G01Y181327D01*
X444531Y181827D01*
X464531D01*
G37*
G36*
G01X438527Y471073D02*
G03I-640J0D01*
G37*
G36*
G01X524600Y409238D02*
G02X524100Y409738I0J500D01*
G01Y429964D01*
G02X525636Y430809I1000J0D01*
G03X526588Y430582I805J1268D01*
G02X527622Y429940I99J-995D01*
G03X530453Y429993I1406J529D01*
G02X531417Y430676I948J-317D01*
G03X530015Y432654I23J1502D01*
G02X529051Y431971I-948J317D01*
G03X528880Y431964I-24J-1502D01*
G02X527846Y432606I-99J995D01*
G03X525060Y432669I-1406J-529D01*
G02X524600Y432366I-460J197D01*
G02X524100Y432866I0J500D01*
G01Y433800D01*
X522778Y435122D01*
G02Y435829I354J353D01*
G01X523914Y436964D01*
X524045Y436998D01*
G03X522213Y438830I-378J1454D01*
G01X522179Y438699D01*
X518902Y435422D01*
X516374D01*
X516291Y435452D01*
G03X515269I-511J-1413D01*
G01X515186Y435422D01*
X504978D01*
G02X503985Y436543I0J1000D01*
G03X501003I-1491J182D01*
G02X500010Y435422I-993J-121D01*
G01X494769D01*
X492860Y437331D01*
Y451633D01*
X495531Y454304D01*
X504706D01*
X507882Y451128D01*
G02X508012Y450648I-354J-353D01*
G03X509806Y448803I1452J-383D01*
G01X509862Y448816D01*
X534867D01*
X537090Y451039D01*
Y464125D01*
X537955Y464990D01*
X540391D01*
G02X541329Y463643I0J-1000D01*
G03X544147I1409J-520D01*
G02X545085Y464990I938J347D01*
G01X564288D01*
X567540Y461738D01*
Y448030D01*
X546870Y427360D01*
Y426426D01*
G02X546723Y426072I-500J0D01*
G01X546330Y425680D01*
Y419989D01*
X546042Y419701D01*
Y410450D01*
X544830Y409238D01*
X524600D01*
G37*
G36*
G01X490900Y485012D02*
X491310Y485422D01*
X496502D01*
X496740Y485184D01*
Y482292D01*
X496010Y481562D01*
X491100D01*
X490900Y481762D01*
Y485012D01*
G37*
G36*
G01X576290Y531261D02*
X596120Y511431D01*
Y398083D01*
X594613Y396576D01*
X594481Y396542D01*
G03X595016Y393594I377J-1454D01*
G02X596120Y392600I104J-995D01*
G01Y392414D01*
X596075Y392315D01*
G03Y391065I1365J-625D01*
G01X596120Y390966D01*
Y388033D01*
X596770Y387383D01*
Y381077D01*
X541705Y326012D01*
X510069D01*
X506940Y329141D01*
Y356276D01*
G02X507446Y356776I500J0D01*
G03Y363780I43J3502D01*
G02X506940Y364280I-6J500D01*
G01Y380284D01*
X528435Y401779D01*
X542167D01*
X547044Y406656D01*
Y419286D01*
X547332Y419574D01*
Y425265D01*
X568710Y446643D01*
Y477833D01*
X563708Y482835D01*
G02X563580Y483325I353J354D01*
G01X563619Y483462D01*
X563648Y483514D01*
G03X561554Y485532I-1308J738D01*
G02X560938Y485604I-262J426D01*
G01X543454Y503088D01*
X525825D01*
X519981Y508932D01*
G02X520186Y510503I708J707D01*
G03X520891Y511452I-756J1298D01*
G02X522018Y512208I973J-232D01*
G03X520789Y514041I232J1484D01*
G02X519662Y513285I-973J232D01*
G03X518132Y512557I-232J-1484D01*
G02X516561Y512352I-864J503D01*
G01X511170Y517743D01*
X506182D01*
X505360Y518565D01*
Y520483D01*
G02X505548Y520874I500J0D01*
G01X505549Y520875D01*
G03X503449Y522999I-936J1175D01*
G01X503448Y522998D01*
G02X503062Y522815I-387J317D01*
G01X502608D01*
X493428Y531995D01*
Y573921D01*
X494500Y574993D01*
Y598525D01*
X500080Y604105D01*
X508111D01*
X515371Y596845D01*
X549348D01*
X554468Y591725D01*
Y553387D01*
X560831Y547024D01*
G02X560500Y545390I-707J-707D01*
G03X559981Y542958I565J-1392D01*
G02X559890Y541490I-722J-692D01*
G03X560359Y538901I948J-1165D01*
G02X560947Y537530I-318J-948D01*
G03X562787Y538319I1361J-635D01*
G02X562199Y539690I318J948D01*
G03X562315Y540051I-1361J636D01*
G02X562902Y540451I492J-91D01*
G03X564571Y541339I286J1474D01*
G02X566199Y541656I921J-390D01*
G01X576290Y531565D01*
Y531261D01*
G37*
G36*
G01X498768Y420120D02*
Y432011D01*
G02X499268Y432511I500J0D01*
G01X508757D01*
X508857Y432465D01*
G03X510115I629J1364D01*
G01X510215Y432511D01*
X518000D01*
G02X518500Y432011I0J-500D01*
G01Y420120D01*
G02X518000Y419620I-500J0D01*
G01X499268D01*
G02X498768Y420120I0J500D01*
G37*
G36*
G01X505265Y463443D02*
X504341Y464367D01*
X504304Y464449D01*
G03X504158Y464700I-1366J-626D01*
G03X504107Y464766I-1214J-885D01*
G01X503996Y464904D01*
Y484918D01*
X506046Y486968D01*
X532381D01*
X532472Y486931D01*
G03X533604I566J1392D01*
G01X533695Y486968D01*
X537381D01*
X537472Y486931D01*
G03X538604I566J1392D01*
G01X538695Y486968D01*
X553403D01*
X555690Y484681D01*
Y468359D01*
X554971Y467640D01*
X540311D01*
X539432Y468519D01*
Y471173D01*
G02X540634Y472152I1000J0D01*
G03X542019Y472580I304J1471D01*
G03X541272Y475087I-1081J1043D01*
G03X539522Y474125I-335J-1464D01*
G02X537882Y473777I-933J359D01*
G01X536794Y474865D01*
G02X536793Y475572I353J354D01*
G03X537164Y477075I-1064J1060D01*
G03X534801Y477813I-1435J-443D01*
G03X534236Y476797I928J-1181D01*
G01X534217Y476623D01*
X533727Y476133D01*
X513075D01*
X511415Y474473D01*
Y474354D01*
X511322Y474223D01*
G03X511044Y473352I1223J-870D01*
G01Y464828D01*
X509659Y463443D01*
X505265D01*
G37*
G36*
G01X512045Y453478D02*
Y453479D01*
Y473352D01*
G02X512545Y473852I500J0D01*
G01X534280D01*
G02X534780Y473352I0J-500D01*
G01Y451873D01*
G02X534280Y451373I-500J0D01*
G01X517462D01*
X512868D01*
X512045Y452196D01*
Y453478D01*
G37*
G36*
G01X584865Y221718D02*
G03X582549I-1158J-956D01*
G02X582163Y221536I-386J318D01*
G01X581163D01*
G02X580799Y221693I0J500D01*
G03X578615I-1092J-1031D01*
G02X578251Y221536I-364J343D01*
G01X573690D01*
X573567Y221414D01*
X558768D01*
X554052Y226130D01*
Y232609D01*
X553386Y233275D01*
X551731Y234930D01*
X548961D01*
X547486Y236405D01*
X547458Y236558D01*
G03X546252Y237764I-1477J-271D01*
G01X546099Y237792D01*
X542884Y241007D01*
Y258440D01*
X542528Y258796D01*
Y267583D01*
X548183Y273238D01*
X550227D01*
X550367Y273119D01*
G03X552315I974J1143D01*
G01X552455Y273238D01*
X558083D01*
X562703Y277858D01*
X569654D01*
X569680Y277831D01*
X585370D01*
X595295Y267906D01*
X595323Y267864D01*
G03X595743Y267444I1251J831D01*
G01X595785Y267416D01*
X595903Y267298D01*
X596016D01*
X596094Y267272D01*
G03X597054I480J1423D01*
G01X597132Y267298D01*
X599343D01*
X613438Y253203D01*
Y226603D01*
X608188Y221353D01*
X604249D01*
X604066Y221536D01*
X597286D01*
X597058Y221664D01*
X596990Y221776D01*
G03X594424I-1283J-781D01*
G02X593997Y221535I-428J259D01*
G01X593336D01*
X593098Y221678D01*
X593033Y221801D01*
G03X590381I-1326J-706D01*
G01X590316Y221678D01*
X590079Y221536D01*
X589222D01*
G02X588845Y221708I0J500D01*
G01X588844Y221709D01*
G03X586570I-1137J-981D01*
G02X586192Y221536I-378J327D01*
G01X585251D01*
G02X584865Y221718I0J500D01*
G37*
G36*
G01X546411Y622690D02*
X545910Y623191D01*
Y633541D01*
G02X546410Y634041I500J0D01*
G01X554999D01*
X555202Y633838D01*
X559974D01*
X560054Y633758D01*
Y622797D01*
X559947Y622690D01*
X546411D01*
G37*
G36*
G01X579930Y313641D02*
G03I-762J0D01*
G37*
G36*
G01X584615Y313783D02*
G03I-762J0D01*
G37*
G36*
G01X654590Y613000D02*
G03X656327Y611263I1480J-257D01*
G02X656766Y611124I86J-493D01*
G01X657220Y610670D01*
Y604206D01*
G02X656007Y603229I-1000J0D01*
G03Y600293I-319J-1468D01*
G02X657220Y599316I213J-977D01*
G01Y594297D01*
G02X655910Y593346I-1000J0D01*
G03Y590490I-465J-1428D01*
G02X657220Y589539I310J-951D01*
G01Y577781D01*
X651550Y572111D01*
X638446D01*
G02X638057Y572296I-1J500D01*
G03X635723I-1167J-945D01*
G01X635651Y572208D01*
X635448Y572111D01*
X627372D01*
G02X626372Y573124I0J1000D01*
G03X624147Y574460I-1502J19D01*
G01X624001Y574379D01*
X623672Y574426D01*
X621050Y577048D01*
Y582428D01*
X617850Y585628D01*
Y585737D01*
X616476Y587110D01*
Y609192D01*
X616390Y609278D01*
Y611591D01*
X613882Y614099D01*
X613866Y614279D01*
G03X612506Y615639I-1496J-136D01*
G01X612326Y615655D01*
X609100Y618881D01*
Y625381D01*
X611231Y627512D01*
X613386D01*
G02X614307Y626122I0J-1000D01*
G03X617073I1383J-586D01*
G02X617994Y627512I921J390D01*
G01X623036D01*
X623156Y627439D01*
G03X624724I784J1281D01*
G01X624844Y627512D01*
X628689D01*
X628828Y627398D01*
G03X629253Y627153I953J1161D01*
G02X629734Y625662I-351J-936D01*
G03X630825Y626323I1250J-833D01*
G02X630525Y627254I-52J497D01*
G03X630734Y627398I-745J1304D01*
G01X630873Y627512D01*
X635091D01*
X635381Y627234D01*
X635389Y627033D01*
G03X638391I1501J62D01*
G02X638890Y627512I499J-21D01*
G01X642649D01*
G02X643145Y627073I0J-500D01*
G03X645834Y626351I1491J184D01*
G02X647339Y626456I798J-602D01*
G01X647591Y626204D01*
X647617Y625831D01*
X647504Y625681D01*
G03X648905Y623286I1197J-907D01*
G02X650040Y622295I135J-991D01*
G01Y617870D01*
X650998Y616912D01*
Y616891D01*
X654451Y613439D01*
G02X654590Y613000I-354J-353D01*
G37*
G36*
G01X606236Y601159D02*
G03I-696J0D01*
G37*
G36*
G01X634582Y412197D02*
G03X634076Y412453I-919J-1188D01*
G02X633714Y412934I138J481D01*
G01Y416087D01*
X637417Y419790D01*
X650522D01*
G02X651016Y419368I0J-500D01*
G02X650676Y418814I-494J-78D01*
G03X650076Y418447I462J-1429D01*
G02X649416Y418406I-353J354D01*
G03X649555Y416159I-923J-1185D01*
G02X650215Y416200I353J-354D01*
G03X652381Y418228I923J1185D01*
G02X653208Y419790I827J562D01*
G01X661300D01*
G02X662249Y418474I0J-1000D01*
G03X664554Y416782I1425J-475D01*
G02X665213Y416718I293J-405D01*
G03X667676Y418371I1099J1024D01*
G02X668584Y419790I908J419D01*
G01X677911D01*
X681272Y416429D01*
Y409835D01*
G02X679699Y409016I-1000J0D01*
G03X677517Y407069I-862J-1231D01*
G01X677545Y407018D01*
X677613Y406768D01*
X677422Y406380D01*
X677347Y406314D01*
G03X679659Y405901I991J-1129D01*
G01X679631Y405952D01*
X679563Y406202D01*
X679754Y406590D01*
X679829Y406656D01*
G03X680248Y407268I-992J1128D01*
G01X680298Y407404D01*
X680467Y407534D01*
G02X681272Y407138I305J-396D01*
G01Y394807D01*
G02X679758Y393949I-1000J0D01*
G03X677552Y392214I-772J-1288D01*
G02X677198Y391116I-955J-298D01*
G03X679533Y390362I901J-1201D01*
G02X679887Y391460I955J298D01*
G03X680326Y391982I-900J1202D01*
G02X681272Y391756I446J-226D01*
G01Y379461D01*
X678358Y376547D01*
G02X677775Y376457I-353J354D01*
G03X675582Y375176I-692J-1333D01*
G02X675082Y374693I-500J17D01*
G01X664499D01*
G02X663656Y376231I0J1000D01*
G03X661124I-1266J808D01*
G02X660281Y374693I-843J-538D01*
G01X654191D01*
G02X653371Y376265I0J1000D01*
G03X650907I-1232J860D01*
G02X650087Y374693I-820J-572D01*
G01X649314D01*
X649195Y374764D01*
G03X647655I-770J-1290D01*
G01X647536Y374693D01*
X646337D01*
X645943Y375087D01*
G02X646085Y376619I707J707D01*
G03X643997Y378707I-849J1239D01*
G02X642465Y378565I-825J565D01*
G01X642082Y378948D01*
G02X642169Y380439I707J707D01*
G03X640059Y382549I-933J1177D01*
G02X638568Y382462I-784J620D01*
G01X637474Y383556D01*
G02X637705Y385143I707J707D01*
G03X636999Y387966I-715J1321D01*
G02X636009Y389042I7J1000D01*
G03X634633Y390653I-1498J114D01*
G02X633714Y391650I81J997D01*
G01Y401723D01*
X635986D01*
G03X636739Y404374I951J1162D01*
G01X636085D01*
X633714Y406745D01*
Y409084D01*
G02X634077Y409565I500J0D01*
G03X634499Y409761I-414J1444D01*
G02X635667Y409722I557J-831D01*
G03X635750Y412158I919J1188D01*
G02X634582Y412197I-557J831D01*
G37*
G36*
G01X634270Y403707D02*
G03I-640J0D01*
G37*
G36*
G01X625340Y563591D02*
Y554731D01*
X650850D01*
Y563591D01*
X625340D01*
G37*
G36*
G01X694055Y575251D02*
X692907Y576399D01*
X692871Y576470D01*
G03X692213Y577128I-1339J-681D01*
G01X692142Y577164D01*
X691780Y577526D01*
G02Y578233I354J354D01*
G01X691867Y578319D01*
X691984Y578356D01*
G03X692434Y580990I-452J1433D01*
G02Y582588I601J799D01*
G03Y584990I-902J1201D01*
G02Y586588I601J799D01*
G03X690630I-902J1201D01*
G02Y584990I-601J-799D01*
G03Y582588I902J-1201D01*
G02Y580990I-601J-799D01*
G03X690305Y580655I902J-1201D01*
G02X688781Y580525I-817J577D01*
G01X660448Y608858D01*
G02X660346Y609420I353J354D01*
G03X658357Y611409I-1366J623D01*
G02X657795Y611511I-208J455D01*
G01X657599Y611707D01*
X657495Y611810D01*
X657432Y612094D01*
X657482Y612231D01*
G03X657129Y613809I-1412J513D01*
G01X657063Y613874D01*
X656897Y614243D01*
X657014Y614561D01*
X657061Y614622D01*
G03X654624Y616374I-1187J919D01*
G02X653085Y616221I-832J555D01*
G01X652000Y617306D01*
Y621233D01*
X658450Y627683D01*
X667138D01*
X697982Y596839D01*
X713570D01*
X717490Y592919D01*
Y575751D01*
G02X716990Y575251I-500J0D01*
G01X694055D01*
G37*
G36*
G01X667207Y364359D02*
G02X667636Y364116I0J-500D01*
G03X670214I1289J771D01*
G01X670282Y364229D01*
X670510Y364359D01*
X677630D01*
G02X678130Y363859I0J-500D01*
G01Y355029D01*
G02X677630Y354529I-500J0D01*
G01X655950D01*
G02X655450Y355029I0J500D01*
G01Y363859D01*
G02X655950Y364359I500J0D01*
G01X667207D01*
G37*
G36*
G01X690880Y119848D02*
G03X688120I-1380J593D01*
G02X687187Y118486I-932J-362D01*
G01X685544D01*
X676480Y127550D01*
Y153220D01*
X682780Y159520D01*
X758047D01*
X765600Y151967D01*
Y121506D01*
X762580Y118486D01*
X691813D01*
G02X690880Y119848I-1J1000D01*
G37*
G36*
G01X677101Y198112D02*
X676160Y199053D01*
Y238466D01*
X678351Y240657D01*
X726050D01*
X727370Y239337D01*
Y225918D01*
G03Y218804I6605J-3557D01*
G01Y201302D01*
X724180Y198112D01*
X718884D01*
G02X718427Y198408I0J500D01*
G03X704723I-6852J-3053D01*
G02X704266Y198112I-457J204D01*
G01X677101D01*
G37*
G36*
G01X745010Y315263D02*
X746280Y316533D01*
X757594D01*
X757930Y316197D01*
Y309583D01*
X757375Y309028D01*
X745610D01*
X745010Y309628D01*
Y315263D01*
G37*
%LPC*%
G75*
G36*
G01X113580Y534050D02*
G02X111601Y534077I-1005J-1116D01*
G03X111622Y535581I-649J761D01*
G02X113601Y535554I1005J1116D01*
G03X113580Y534050I649J-761D01*
G37*
G36*
G01X115090Y542075D02*
G02X112790Y542142I-1178J-931D01*
G03X112827Y543427I-748J665D01*
G02X115127Y543360I1178J931D01*
G03X115090Y542075I748J-665D01*
G37*
G36*
G01X213766Y300944D02*
G02X211432I-1167J-946D01*
G03Y302202I-777J629D01*
G02X211437Y304100I1167J946D01*
G03X211441Y305361I-774J633D01*
G02X213772Y305353I1169J944D01*
G03X213768Y304092I774J-633D01*
G02X213766Y302202I-1169J-944D01*
G03Y300944I777J-629D01*
G37*
G36*
G01X207466Y304094D02*
G02X205132I-1167J-946D01*
G03Y305352I-777J629D01*
G02X207466I1167J946D01*
G03Y304094I777J-629D01*
G37*
G36*
G01X181437Y315441D02*
G02X180979Y317829I-1095J1028D01*
G03X182133Y318051I424J906D01*
G02X184130Y318224I1095J-1028D01*
G03X185378Y318261I601J799D01*
G02X185448Y315915I972J-1145D01*
G03X184200Y315878I-601J-799D01*
G02X182591Y315663I-972J1145D01*
G03X181437Y315441I-424J-906D01*
G37*
G36*
G01X163089Y325441D02*
G02X161341Y325730I-1072J-1052D01*
G03X161352Y326617I-226J446D01*
G02X161091Y326795I711J1323D01*
G03X160467Y326813I-323J-382D01*
G02X160536Y329158I-903J1200D01*
G03X161160Y329140I323J382D01*
G02X163107Y326860I903J-1200D01*
G03X163089Y325441I696J-718D01*
G37*
G36*
G01X152618Y377410D02*
G02X150804Y376842I-559J-1394D01*
G03X150342Y378320I-835J550D01*
G02X149622Y380500I560J1394D01*
G03X149471Y381737I-852J524D01*
G02X149833Y384142I1053J1071D01*
G03X150351Y385239I-460J888D01*
G02X152511Y384220I1469J315D01*
G03X151993Y383123I460J-888D01*
G02X151804Y382022I-1469J-315D01*
G03X151955Y380785I852J-524D01*
G02X152156Y378888I-1053J-1071D01*
G03X152618Y377410I835J-550D01*
G37*
G36*
G01X195912Y307417D02*
G03X194712I-600J-800D01*
G02X193395Y310062I-900J1202D01*
G03X193755Y310572I-139J480D01*
G02X196460Y311558I1499J91D01*
G03X197909Y311391I803J596D01*
G02X198804Y308745I971J-1146D01*
G03X198288Y308339I-25J-499D01*
G02X195912Y307417I-1476J280D01*
G37*
G36*
G01X186407Y308714D02*
G03X185994Y309184I-500J-23D01*
G02X185354Y309461I260J1479D01*
G03X184154I-600J-800D01*
G02X182354I-900J1202D01*
G03X181154I-600J-800D01*
G02Y311865I-900J1202D01*
G03X182354I600J800D01*
G02X184154I900J-1202D01*
G03X185354I600J800D01*
G02X187754Y310733I900J-1202D01*
G03X188167Y310263I500J23D01*
G02X186407Y308714I-260J-1479D01*
G37*
G36*
G01X195521Y315883D02*
G03X194892Y315888I-318J-386D01*
G02X192866Y316031I-935J1176D01*
G03X192168Y316058I-363J-344D01*
G02X192250Y318204I-1009J1113D01*
G03X192948Y318177I363J344D01*
G02X194912Y318223I1009J-1113D01*
G03X195541Y318218I318J386D01*
G02X195521Y315883I935J-1176D01*
G37*
G36*
G01X161545Y335540D02*
G03X160431Y335250I-351J-937D01*
G02X158258Y335124I-1146J970D01*
G03X157124Y335288I-684J-729D01*
G02X157475Y337725I-676J1341D01*
G03X158609Y337561I684J729D01*
G02X159811Y337627I676J-1341D01*
G03X160925Y337917I351J937D01*
G02X161545Y335540I1146J-970D01*
G37*
G36*
G01X204114Y311412D02*
G02X201936Y313439I-948J1165D01*
G03X201893Y314645I-818J575D01*
G02X203976Y316782I1165J948D01*
G03X205272Y316844I612J791D01*
G02X207466Y314802I1028J-1096D01*
G03Y313544I777J-629D01*
G02X207481Y313525I-1172J-940D01*
G03X208267I393J309D01*
G02X208503Y311431I1182J-927D01*
G03X207245I-629J-777D01*
G02X205366Y311421I-946J1167D01*
G03X204114Y311412I-620J-784D01*
G37*
G36*
G01X243491Y44602D02*
G02Y46406I-1201J902D01*
G03X245089I799J601D01*
G02X247491I1201J-902D01*
G03X249089I799J601D01*
G02Y44602I1201J-902D01*
G03X247491I-799J-601D01*
G02X245089I-1201J902D01*
G03X243491I-799J-601D01*
G37*
G36*
G01X243191Y20317D02*
G02Y22121I-1201J902D01*
G03X244789I799J601D01*
G02X247191I1201J-902D01*
G03X248789I799J601D01*
G02Y20317I1201J-902D01*
G03X247191I-799J-601D01*
G02X244789I-1201J902D01*
G03X243191I-799J-601D01*
G37*
G36*
G01X223191D02*
G02Y22121I-1201J902D01*
G03X224789I799J601D01*
G02X227191I1201J-902D01*
G03X228789I799J601D01*
G02Y20317I1201J-902D01*
G03X227191I-799J-601D01*
G02X224789I-1201J902D01*
G03X223191I-799J-601D01*
G37*
G36*
G01X214805Y324174D02*
G02X215154Y327149I281J1475D01*
G03X215664Y327539I22J500D01*
G02X218331Y326307I1465J-332D01*
G03Y325107I800J-600D01*
G02X216600Y322801I-1202J-900D01*
G02X214805Y324174I-1500J-101D01*
G37*
G36*
G01X207592Y323754D02*
G02X207325Y326543I408J1446D01*
G03X207473Y327133I-180J359D01*
G02X207217Y328244I1227J868D01*
G03X206924Y328696I-396J64D01*
G02X206773Y331553I386J1453D01*
G03X207021Y332018I-143J375D01*
G02X209022Y330952I1464J338D01*
G03X208774Y330487I143J-375D01*
G02X208793Y329905I-1464J-339D01*
G03X209086Y329453I396J-64D01*
G02X209375Y326657I-386J-1453D01*
G03X209227Y326067I180J-359D01*
G02X209435Y324752I-1227J-868D01*
G03X209708Y324246I383J-120D01*
G02X207865Y323248I-409J-1446D01*
G03X207592Y323754I-383J120D01*
G37*
G36*
G01X321999Y559828D02*
G03X321983Y560486I-384J320D01*
G02X321917Y562444I1105J1017D01*
G03X321957Y563643I-780J626D01*
G02X324359Y563562I1231J860D01*
G03X324319Y562363I780J-626D01*
G02X324243Y560542I-1231J-861D01*
G03X324259Y559884I384J-320D01*
G02X324327Y557929I-1105J-1017D01*
G03Y557305I391J-312D01*
G02Y555429I-1173J-938D01*
G03Y554805I391J-312D01*
G02X321981I-1173J-938D01*
G03Y555429I-391J312D01*
G02Y557305I1173J938D01*
G03Y557929I-391J312D01*
G02X321999Y559828I1173J938D01*
G37*
G36*
G01X245338Y426635D02*
G03Y425985I380J-325D01*
G02X243054I-1142J-975D01*
G03Y426635I-380J325D01*
G02X245338I1142J975D01*
G37*
G36*
G01Y418635D02*
G03Y417985I380J-325D01*
G02X243054I-1142J-975D01*
G03Y418635I-380J325D01*
G02X245338I1142J975D01*
G37*
G36*
G01X327511Y546656D02*
G02X327137Y544529I841J-1244D01*
G03X325768Y544769I-809J-588D01*
G02X326142Y546896I-841J1244D01*
G03X327511Y546656I809J588D01*
G37*
G36*
G01X319878Y540062D02*
G02X319369Y542299I-1200J903D01*
G03X320628Y542586I460J888D01*
G02X323018Y542598I1200J-904D01*
G03X324521Y542504I793J610D01*
G02X326609Y542549I1067J-1057D01*
G03X327810Y542428I680J733D01*
G02X327571Y540044I782J-1282D01*
G03X326370Y540165I-680J-733D01*
G02X324398Y540531I-782J1282D01*
G03X322895Y540625I-793J-610D01*
G02X321137Y540349I-1067J1057D01*
G03X319878Y540062I-460J-888D01*
G37*
G36*
G01X208254Y354262D02*
G02X205924Y353782I-980J-1138D01*
G03X205677Y354978I-899J438D01*
G02X205632Y357214I980J1138D01*
G03X205672Y357902I-342J365D01*
G02X205670Y359844I1145J972D01*
G03X205732Y361053I-764J645D01*
G02X208120Y360930I1241J847D01*
G03X208058Y359721I764J-645D01*
G02X207842Y357776I-1241J-847D01*
G03X207802Y357088I342J-365D01*
G02X208007Y355458I-1145J-972D01*
G03X208254Y354262I899J-438D01*
G37*
G36*
G01X338723Y555180D02*
G03Y554556I391J-312D01*
G02X336377I-1173J-938D01*
G03Y555180I-391J312D01*
G02Y557056I1173J938D01*
G03Y557680I-391J312D01*
G02X338723I1173J938D01*
G03Y557056I391J-312D01*
G02Y555180I-1173J-938D01*
G37*
G36*
G01X224349Y478031D02*
G02X222403Y477223I-562J-1393D01*
G03X221856Y478540I-921J390D01*
G02X223802Y479348I562J1393D01*
G03X224349Y478031I921J-390D01*
G37*
G36*
G01X278521Y480124D02*
G02Y482270I-1051J1073D01*
G03X279919I699J715D01*
G02X280283Y482533I1052J-1072D01*
G03X280814Y483574I-457J889D01*
G02X282985Y482467I1484J229D01*
G03X282454Y481426I457J-889D01*
G02X279919Y480124I-1484J-229D01*
G03X278521I-699J-715D01*
G37*
G36*
G01X266632Y492621D02*
G02X266558Y490682I1109J-1013D01*
G03X265033Y490741I-787J-616D01*
G02X265107Y492680I-1109J1013D01*
G03X266632Y492621I787J616D01*
G37*
G36*
G01X300000Y497340D02*
G02X298713Y495992I209J-1487D01*
G03X297579Y497076I-996J94D01*
G02X298866Y498424I-209J1487D01*
G03X300000Y497340I996J-94D01*
G37*
G36*
G01X272443Y497212D02*
G02X270400Y497195I-1014J-917D01*
G03X270388Y498524I-753J658D01*
G02X272431Y498541I1014J917D01*
G03X272443Y497212I753J-658D01*
G37*
G36*
G01X285006Y498355D02*
G02X282934Y500427I-982J1090D01*
G03X282966Y501730I-742J670D01*
G02X285082I1058J865D01*
G03X285114Y500427I774J-633D01*
G02X285244Y500260I-1090J-982D01*
G03X286065Y500245I416J278D01*
G02X286308Y498386I1108J-801D01*
G03X285006Y498355I-633J-774D01*
G37*
G36*
G01X265937Y503811D02*
G02X264140Y501501I-816J-1220D01*
G03X262837Y501533I-670J-742D01*
G02X260952Y503501I-864J1059D01*
G03Y504831I-747J665D01*
G02Y506651I1020J910D01*
G03Y507981I-747J665D01*
G02X260913Y509756I1020J910D01*
G03X260882Y511058I-774J633D01*
G02X262909Y513169I1090J982D01*
G03X264185I638J770D01*
G02X266212Y511058I937J-1129D01*
G03X266180Y509756I742J-670D01*
G02X266230Y509690I-1064J-858D01*
G03X267052Y509705I406J292D01*
G02X269401Y507954I1221J-814D01*
G03Y506678I770J-638D01*
G02X267290Y504651I-1129J-937D01*
G03X265987Y504683I-670J-742D01*
G02X265922Y504632I-876J1049D01*
G03X265937Y503811I292J-405D01*
G37*
G36*
G01X243984Y501570D02*
G02Y503612I-909J1021D01*
G03X245315I665J746D01*
G02X247134Y503611I909J-1021D01*
G03X248464I665J747D01*
G02X248640Y503744I909J-1020D01*
G03Y504588I-269J422D01*
G02X248354Y506651I734J1153D01*
G03Y507981I-747J665D01*
G02X248315Y509756I1020J910D01*
G03X248284Y511058I-774J633D01*
G02X248199Y511161I1088J984D01*
G03X247399I-400J-299D01*
G02X247161Y513169I-1175J879D01*
G03X248437I638J770D01*
G02X250464Y511058I937J-1129D01*
G03X250433Y509756I743J-669D01*
G02X250527Y509625I-1062J-861D01*
G03X251371I422J269D01*
G02X253433Y509912I1153J-734D01*
G03X254764I665J746D01*
G02X256693Y507981I909J-1021D01*
G03Y506651I747J-665D01*
G02Y504831I-1020J-910D01*
G03Y503501I747J-665D01*
G02X254764Y501570I-1020J-910D01*
G03X253433I-665J-746D01*
G02X251614Y501571I-909J1021D01*
G03X250284I-665J-747D01*
G02X248464I-910J1020D01*
G03X247134I-665J-747D01*
G02X245315Y501570I-910J1020D01*
G03X243984I-665J-746D01*
G37*
G36*
G01X275487Y501567D02*
G02X275485Y503618I-905J1025D01*
G03X276807Y503619I660J751D01*
G02X276809Y501568I905J-1025D01*
G03X275487Y501567I-660J-751D01*
G37*
G36*
G01X262909Y520360D02*
G02X260843Y522426I-937J1129D01*
G03Y523702I-770J638D01*
G02Y525576I1129J937D01*
G03Y526852I-770J638D01*
G02X262909Y528918I1129J937D01*
G03X264185I638J770D01*
G02X266059I937J-1129D01*
G03X267335I638J770D01*
G02X269401Y526852I937J-1129D01*
G03Y525576I770J-638D01*
G02Y523702I-1129J-937D01*
G03Y522426I770J-638D01*
G02X267335Y520360I-1129J-937D01*
G03X266059I-638J-770D01*
G02X264185I-937J1129D01*
G03X262909I-638J-770D01*
G37*
G36*
G01X250311Y523510D02*
G02X248245Y525576I-937J1129D01*
G03Y526852I-770J638D01*
G02X250311Y528918I1129J937D01*
G03X251587I638J770D01*
G02X253460I937J-1129D01*
G03X254737I639J770D01*
G02X256802Y526852I936J-1130D01*
G03Y525576I770J-638D01*
G02X254737Y523510I-1129J-936D01*
G03X253460I-638J-770D01*
G02X251587I-936J1129D01*
G03X250311I-638J-770D01*
G37*
G36*
G01Y532959D02*
G02X248245Y535024I-936J1129D01*
G03Y536301I-770J638D01*
G02Y538174I1129J936D01*
G03Y539450I-770J638D01*
G02X250311Y541516I1129J937D01*
G03X251587I638J770D01*
G02X253460I937J-1129D01*
G03X254737I639J770D01*
G02X256802Y539450I936J-1130D01*
G03Y538174I770J-638D01*
G02Y536301I-1129J-936D01*
G03Y535024I770J-638D01*
G02X254737Y532959I-1129J-936D01*
G03X253460I-638J-770D01*
G02X251587I-936J1129D01*
G03X250311I-638J-770D01*
G37*
G36*
G01X262909D02*
G02X260843Y535024I-936J1129D01*
G03Y536301I-770J638D01*
G02Y538174I1129J936D01*
G03Y539450I-770J638D01*
G02X262909Y541516I1129J937D01*
G03X264185I638J770D01*
G02X266059I937J-1129D01*
G03X267335I638J770D01*
G02X269401Y539450I937J-1129D01*
G03Y538174I770J-638D01*
G02Y536301I-1129J-936D01*
G03Y535024I770J-638D01*
G02X267335Y532959I-1130J-936D01*
G03X266059I-638J-770D01*
G02X264185I-937J1129D01*
G03X262909I-638J-770D01*
G37*
G36*
G01X281811Y532963D02*
G02X279745Y535028I-936J1129D01*
G03Y536305I-770J639D01*
G02X282003I1129J936D01*
G03Y535028I770J-638D01*
G02X282049Y534971I-1118J-949D01*
G03X282849I400J299D01*
G02X284961Y535221I1175J-879D01*
G03X286237I638J770D01*
G02X288110I937J-1129D01*
G03X289387I639J770D01*
G02X291260I936J-1129D01*
G03X292536I638J770D01*
G02Y532963I937J-1129D01*
G03X291260I-638J-770D01*
G02X289387I-936J1129D01*
G03X288110I-638J-770D01*
G02X286237I-936J1129D01*
G03X284961I-638J-770D01*
G02X283087I-937J1129D01*
G03X281811I-638J-770D01*
G37*
G36*
G01X288110Y539262D02*
G02X286045Y541328I-936J1130D01*
G03Y542604I-770J638D01*
G02X285999Y542662I1126J940D01*
G03X285199I-400J-299D01*
G02X283087Y542412I-1175J879D01*
G03X281811I-638J-770D01*
G02Y544670I-937J1129D01*
G03X283087I638J770D01*
G02X284961I937J-1129D01*
G03X286237I638J770D01*
G02X288110I937J-1129D01*
G03X289387I639J770D01*
G02X291452Y542604I936J-1130D01*
G03Y541328I770J-638D01*
G02X291498Y541270I-1126J-940D01*
G03X292298I400J299D01*
G02X292536Y539262I1175J-879D01*
G03X291260I-638J-770D01*
G02X289387I-936J1129D01*
G03X288110I-638J-770D01*
G37*
G36*
G01X250494Y550782D02*
G02X248236Y550761I-1120J-947D01*
G03X248224Y552037I-776J631D01*
G02X248215Y553921I1120J947D01*
G03Y555197I-770J638D01*
G02X248135Y555304I1134J931D01*
G03X247321Y555319I-412J-283D01*
G02X245204Y557044I-1097J815D01*
G03Y558374I-747J665D01*
G02X245071Y558549I1018J912D01*
G03X244228I-421J-268D01*
G02X243984Y560305I-1153J735D01*
G03X245315I665J746D01*
G02X245490Y560437I908J-1022D01*
G03Y561281I-269J422D01*
G02X247244Y561524I734J1153D01*
G03Y560194I747J-665D01*
G02Y558374I-1020J-910D01*
G03Y557044I747J-665D01*
G02X247321Y556949I-1022J-907D01*
G03X248135Y556964I402J298D01*
G02X250473Y555197I1210J-829D01*
G03Y553921I770J-638D01*
G02X250482Y552058I-1129J-937D01*
G03X250494Y550782I776J-631D01*
G37*
G36*
G01X262909Y548707D02*
G02X260843Y550773I-937J1129D01*
G03Y552049I-770J638D01*
G02X260859Y553940I1130J936D01*
G03X260874Y555224I-759J651D01*
G02X263123Y555198I1135J929D01*
G03X263108Y553914I759J-651D01*
G02X263147Y553864I-1137J-927D01*
G03X263948I401J300D01*
G02X266251Y552049I1174J-879D01*
G03Y550772I770J-638D01*
G02X264185Y548707I-1130J-936D01*
G03X262909I-638J-770D01*
G37*
G36*
G01X281674Y550948D02*
G02X279814Y550706I-802J-1107D01*
G03X279783Y552008I-774J633D01*
G02X279700Y552110I1095J976D01*
G03X278899I-401J-300D01*
G02X276789Y551860I-1174J879D01*
G03X275510Y551858I-638J-770D01*
G02X273589Y551895I-939J1127D01*
G03X272286Y551927I-670J-742D01*
G02X270363Y553850I-865J1058D01*
G03X270331Y555153I-774J633D01*
G02X270294Y557074I1090J982D01*
G03Y558353I-769J640D01*
G02X270247Y558412I1124J943D01*
G03X269447I-400J-299D01*
G02X269209Y560420I-1175J879D01*
G03X270485I638J770D01*
G02X270540Y560463I931J-1134D01*
G03Y561262I-301J399D01*
G02X270293Y563370I882J1172D01*
G03Y564647I-770J638D01*
G02X272551I1129J936D01*
G03Y563370I770J-639D01*
G02X272553Y561500I-1129J-936D01*
G03Y560225I771J-638D01*
G02X272549Y558352I-1131J-934D01*
G03Y557073I769J-640D01*
G02X272640Y556952I-1126J-941D01*
G03X273461Y556939I415J278D01*
G02X275441Y557198I1111J-797D01*
G03X276744Y557226I635J772D01*
G02X276848Y557311I979J-1092D01*
G03Y558113I-299J401D01*
G02X278661Y560418I877J1176D01*
G03X279938I638J770D01*
G02X279995Y560463I937J-1128D01*
G03Y561264I-300J401D01*
G02X281811Y563567I879J1174D01*
G03X283087I638J770D01*
G02X283145Y563613I940J-1126D01*
G03Y564413I-299J400D01*
G02X284961Y566717I879J1175D01*
G03X286237I638J770D01*
G02X288110Y566718I937J-1129D01*
G03X289386I638J770D01*
G02X291260I937J-1129D01*
G03X292536I638J770D01*
G02X294602Y564652I937J-1129D01*
G03Y563376I770J-638D01*
G02Y561503I-1129J-936D01*
G03Y560226I770J-638D01*
G02X292537Y558161I-1129J-936D01*
G03X291260Y558160I-638J-770D01*
G02X291202Y558115I-928J1136D01*
G03Y557314I300J-400D01*
G02X289387Y555010I-879J-1175D01*
G03X288111I-638J-770D01*
G02X288053Y554964I-940J1126D01*
G03Y554164I299J-400D01*
G02X286237Y551860I-879J-1175D01*
G03X284961I-638J-770D01*
G02X283087I-937J1129D01*
G03X281811I-638J-770D01*
G02X281689Y551769I-937J1129D01*
G03X281674Y550948I278J-416D01*
G37*
G36*
G01X256802Y553920D02*
G02X254544I-1129J-936D01*
G03Y555197I-770J638D01*
G02Y557069I1129J936D01*
G03Y558346I-770J638D01*
G02X254456Y558464I1130J935D01*
G03X253642Y558487I-415J-279D01*
G02X253421Y560371I-1088J827D01*
G03X254711Y560389I634J773D01*
G02X254794Y560456I962J-1107D01*
G03Y561257I-300J400D01*
G02X254544Y563367I879J1174D01*
G03Y564644I-770J638D01*
G02X256802I1129J936D01*
G03Y563367I770J-638D01*
G02Y561495I-1129J-936D01*
G03Y560218I770J-639D01*
G02Y558346I-1129J-936D01*
G03Y557069I770J-639D01*
G02Y555197I-1129J-936D01*
G03Y553920I770J-639D01*
G37*
G36*
G01X241945Y574829D02*
G03X241871Y575459I-421J270D01*
G02X244309Y577099I1044J1080D01*
G03X245486Y576504I928J373D01*
G02X245249Y573677I374J-1455D01*
G03X244587Y573420I-204J-457D01*
G02X241945Y574829I-1378J598D01*
G37*
G36*
G01X256542Y324130D02*
G02X254776Y322722I-266J-1478D01*
G03X254365Y323238I-500J24D01*
G02X253571Y325780I266J1478D01*
G03X253640Y326404I-353J355D01*
G02X253788Y328217I1265J809D01*
G03X253811Y328858I-372J334D01*
G02Y330700I1187J921D01*
G03X253767Y331363I-395J307D01*
G02X253875Y333604I1052J1072D01*
G03X253952Y334305I-314J389D01*
G02X253906Y336122I1172J939D01*
G03X253860Y337351I-811J585D01*
G02X256227Y337440I1149J967D01*
G03X256273Y336211I811J-585D01*
G02X256068Y334075I-1149J-968D01*
G03X255991Y333374I314J-389D01*
G02X256006Y331514I-1172J-940D01*
G03X256050Y330851I395J-307D01*
G02X256115Y328775I-1052J-1072D01*
G03X256092Y328134I372J-334D01*
G02X255965Y326149I-1187J-921D01*
G03X255896Y325525I353J-355D01*
G02X256131Y324646I-1265J-809D01*
G03X256542Y324130I500J-24D01*
G37*
G36*
G01X274441Y383948D02*
G02X272083Y384540I-964J1152D01*
G03X271012Y385157I-928J-373D01*
G02X272190Y387203I-216J1486D01*
G03X273261Y386586I928J373D01*
G02X274441Y386252I217J-1486D01*
G03X275723I641J767D01*
G02Y383948I964J-1152D01*
G03X274441I-641J-767D01*
G37*
G36*
G01X266581Y390183D02*
G02X268572Y389309I1412J512D01*
G03X268294Y388677I192J-462D01*
G02X266303Y389551I-1412J-512D01*
G03X266581Y390183I-192J462D01*
G37*
G36*
G01X320715Y353301D02*
G02X320643Y355517I-1049J1075D01*
G03X321991Y355560I650J759D01*
G02X322063Y353344I1049J-1075D01*
G03X320715Y353301I-650J-759D01*
G37*
G36*
G01X319572Y336071D02*
G02X317662Y336299I-1092J-1032D01*
G03X317999Y337610I-544J839D01*
G02X320742Y338814I1324J710D01*
G03X321895Y338165I944J329D01*
G02X320713Y336570I315J-1469D01*
G03X319992Y336975I-498J-42D01*
G02X319782Y336890I-667J1346D01*
G03X319572Y336071I153J-476D01*
G37*
G36*
G01X364983Y686477D02*
G03X364718Y686350I74J-494D01*
G03X364460Y686492I-359J-348D01*
G02X363411Y687313I305J1471D01*
G03X362164Y687818I-901J-433D01*
G02X363000Y689878I-518J1410D01*
G03X364247Y689373I901J433D01*
G02X364983Y686477I518J-1410D01*
G37*
G36*
G01X556923Y174381D02*
G02X555308Y175360I-1413J-509D01*
G03X556170Y176424I-135J991D01*
G02X559169Y176492I1498J111D01*
G03X559663Y175978I500J-14D01*
G02X558145Y174518I-17J-1502D01*
G03X557651Y175032I-500J14D01*
G02X557462Y175046I16J1502D01*
G03X556923Y174381I-69J-495D01*
G37*
G36*
G01X559956Y157686D02*
G02X559745Y159899I-1111J1011D01*
G03X561084Y160026I600J800D01*
G02X561459Y160324I1110J-1012D01*
G03X561890Y161585I-490J872D01*
G02X562142Y163157I1384J584D01*
G03X562197Y164404I-753J658D01*
G02X564542Y164301I1214J885D01*
G03X564487Y163054I753J-658D01*
G02X564010Y160860I-1213J-885D01*
G03X563579Y159599I490J-872D01*
G02X561295Y157813I-1384J-584D01*
G03X559956Y157686I-600J-800D01*
G37*
G36*
G01X548825Y142632D02*
G02X548615Y144467I-1282J783D01*
G03X550182Y144645I714J700D01*
G02X550392Y142810I1282J-783D01*
G03X548825Y142632I-714J-700D01*
G37*
G36*
G01X595439Y139632D02*
G02X593936Y138164I-1J-1502D01*
G03X592937Y139187I-1000J23D01*
G02X594440Y140655I1J1502D01*
G03X595439Y139632I1000J-23D01*
G37*
G36*
G01X550748Y134091D02*
G02X549110Y132794I-149J-1495D01*
G03X548218Y133920I-991J131D01*
G02X549856Y135217I149J1495D01*
G03X550748Y134091I991J-131D01*
G37*
G36*
G01X594440Y117692D02*
G02X592881Y119158I-1502J-35D01*
G03X593843Y120181I-38J999D01*
G02X594069Y121008I1502J34D01*
G03X593899Y122269I-850J527D01*
G02X596196Y122578I1021J1101D01*
G03X596366Y121317I850J-527D01*
G02X595402Y118715I-1021J-1101D01*
G03X594440Y117692I38J-999D01*
G37*
G36*
G01X595007Y100323D02*
G02X593872Y98446I311J-1470D01*
G03X592703Y99154I-963J-270D01*
G02X591776Y99253I-312J1469D01*
G03X590398Y98590I-410J-912D01*
G02X589559Y100333I-1455J373D01*
G03X590937Y100996I410J912D01*
G02X591845Y102022I1455J-373D01*
G03X592427Y103273I-365J931D01*
G02X594397Y102356I1423J482D01*
G03X593815Y101105I365J-931D01*
G02X593838Y101031I-1423J-483D01*
G03X595007Y100323I963J270D01*
G37*
G36*
G01X587194Y66900D02*
G02X583956Y65176I-3238J2179D01*
G02X579954Y69178I0J4002D01*
G02X587173Y71402I3952J0D01*
G03X588731Y71283I827J563D01*
G02X588750Y67031I2268J-2116D01*
G03X587194Y66900I-726J-688D01*
G37*
G36*
G01X390249Y19435D02*
G02Y21661I-1009J1113D01*
G03X391591I671J741D01*
G02Y19435I1009J-1113D01*
G03X390249I-671J-741D01*
G37*
G36*
G01X382179Y18783D02*
G02X381970Y16417I811J-1264D01*
G03X380751Y16525I-679J-734D01*
G02X380960Y18891I-811J1264D01*
G03X382179Y18783I679J734D01*
G37*
G36*
G01X438844Y411507D02*
G02X438739Y409342I986J-1133D01*
G03X437356Y409410I-727J-687D01*
G02X437461Y411575I-986J1133D01*
G03X438844Y411507I727J687D01*
G37*
G36*
G01X445497Y410647D02*
G02X444128Y411872I-1477J-273D01*
G03X445183Y413052I72J997D01*
G02X445790Y414549I1477J273D01*
G03X445905Y416083I-580J815D01*
G02X447820Y415938I1045J1079D01*
G03X447705Y414404I580J-815D01*
G02X446552Y411827I-1045J-1079D01*
G03X445497Y410647I-72J-997D01*
G37*
G36*
G01X407088Y412342D02*
G02X404802Y412377I-1158J-956D01*
G03X404822Y413674I-751J660D01*
G02X404878Y415650I1158J956D01*
G03X404966Y416899I-734J679D01*
G02X404944Y416931I1227J867D01*
G03X404178Y417015I-418J-275D01*
G02X404180Y419165I-1048J1076D01*
G03X405407Y419031I699J715D01*
G02X407302Y416735I793J-1276D01*
G03X407214Y415486I734J-679D01*
G02X407108Y413639I-1234J-856D01*
G03X407088Y412342I751J-660D01*
G37*
G36*
G01X423121Y415726D02*
G02X421063Y415749I-1041J-1082D01*
G03X421079Y417206I-677J736D01*
G02X423137Y417183I1041J1082D01*
G03X423121Y415726I677J-736D01*
G37*
G36*
G01X433735Y416173D02*
G02X431537Y414404I-775J-1287D01*
G03X430490Y415079I-947J-320D01*
G02X430114Y418058I-150J1494D01*
G03X430957Y418934I-150J988D01*
G02X433531Y417723I1493J-168D01*
G03X433735Y416173I720J-694D01*
G37*
G36*
G01X405103Y445959D02*
G02X405036Y443603I897J-1204D01*
G03X403797Y443638I-642J-767D01*
G02X403864Y445994I-897J1204D01*
G03X405103Y445959I642J767D01*
G37*
G36*
G01X400168Y451971D02*
G02X397938Y451978I-1118J-1003D01*
G03X397942Y453319I-740J673D01*
G02X397988Y455374I1118J1003D01*
G03X397884Y456867I-714J700D01*
G02X399872Y457006I916J1191D01*
G03X399976Y455513I714J-700D01*
G02X400172Y453312I-916J-1191D01*
G03X400168Y451971I740J-673D01*
G37*
G36*
G01X407936Y592391D02*
G02X405829Y592394I-1055J-1069D01*
G03Y593107I-351J357D01*
G02X408041Y595134I1055J1069D01*
G03X409495Y595043I770J638D01*
G02X411460Y595120I1027J-1096D01*
G03X412084I312J391D01*
G02Y592774I938J-1173D01*
G03X411460I-312J-391D01*
G02X409118Y593413I-938J1173D01*
G03X408210Y593470I-467J-178D01*
G02X407936Y593104I-1325J707D01*
G03Y592391I351J-357D01*
G37*
G36*
G01X531773Y420957D02*
G03X531361Y419866I554J-832D01*
G02X529077Y420728I-1451J-388D01*
G03X529489Y421819I-554J832D01*
G02X531773Y420957I1451J388D01*
G37*
G36*
G01X545509Y456117D02*
G03X544190Y455438I-353J-936D01*
G02X543267Y457229I-1452J385D01*
G03X544586Y457908I353J936D01*
G02X545509Y456117I1452J-385D01*
G37*
G36*
G01X553231Y387976D02*
G02X553120Y390046I-1141J977D01*
G03X554566Y390123I686J727D01*
G02X554677Y388053I1141J-977D01*
G03X553231Y387976I-686J-727D01*
G37*
G36*
G01X550802Y406169D02*
G02Y408333I-1042J1082D01*
G03X552188I693J721D01*
G02X552249Y408389I1046J-1078D01*
G03X552457Y409655I-653J757D01*
G02X554731Y409282I1293J765D01*
G03X554523Y408016I653J-757D01*
G02X552188Y406169I-1293J-765D01*
G03X550802I-693J-721D01*
G37*
G36*
G01X566811Y412661D02*
G02X565015Y414173I-1501J39D01*
G03X565819Y415127I-196J981D01*
G02X567615Y413615I1501J-39D01*
G03X566811Y412661I196J-981D01*
G37*
G36*
G01X574816Y465094D02*
G02X574417Y462797I734J-1311D01*
G03X573174Y463013I-754J-656D01*
G02X573573Y465310I-734J1311D01*
G03X574816Y465094I754J656D01*
G37*
G36*
G01X573636Y468415D02*
G02X573171Y470635I-1196J908D01*
G03X574454Y470904I486J874D01*
G02X574919Y468684I1196J-908D01*
G03X573636Y468415I-486J-874D01*
G37*
G36*
G01X580466Y510105D02*
G02X578277Y509590I-866J-1227D01*
G03X577974Y510881I-880J474D01*
G02X580163Y511396I866J1227D01*
G03X580466Y510105I880J-474D01*
G37*
G36*
G01X563652Y510437D02*
G02X563040Y508418I718J-1320D01*
G03X561678Y508831I-885J-465D01*
G02X562290Y510850I-718J1320D01*
G03X563652Y510437I885J465D01*
G37*
G36*
G01X573325Y509556D02*
G02X571542Y510885I-1495J-145D01*
G03X572345Y511963I-192J981D01*
G02X574128Y510634I1495J145D01*
G03X573325Y509556I192J-981D01*
G37*
G36*
G01X547120Y510711D02*
G02X546700Y508740I880J-1218D01*
G03X545250Y509049I-865J-501D01*
G02X545670Y511020I-880J1218D01*
G03X547120Y510711I865J501D01*
G37*
G36*
G01X545566Y514359D02*
G02X545281Y516461I-1196J908D01*
G03X546684Y516651I607J795D01*
G02X546969Y514549I1196J-908D01*
G03X545566Y514359I-607J-795D01*
G37*
G36*
G01X569175Y526321D02*
G02X566795Y526103I-1107J-1015D01*
G03X566684Y527310I-848J531D01*
G02X566767Y529424I1107J1015D01*
G03X566648Y530983I-681J732D01*
G02X568517Y531126I845J1242D01*
G03X568636Y529567I681J-732D01*
G02X569064Y527528I-845J-1242D01*
G03X569175Y526321I848J-531D01*
G37*
G36*
G01X525172Y527869D02*
G02X524625Y530061I-1234J856D01*
G03X525904Y530381I457J889D01*
G02X528129Y530654I1234J-856D01*
G03X529447I659J752D01*
G02Y528396I991J-1129D01*
G03X528129I-659J-752D01*
G02X526451Y528189I-991J1129D01*
G03X525172Y527869I-457J-889D01*
G37*
G36*
G01X542433Y538715D02*
G02X542385Y540595I-1195J910D01*
G03X543943Y540635I763J646D01*
G02X543991Y538755I1195J-910D01*
G03X542433Y538715I-763J-646D01*
G37*
G36*
G01X504948Y540318D02*
G02X503311Y541731I-1500J-83D01*
G03X504218Y542782I-91J996D01*
G02X504216Y542861I1500J78D01*
G03X503622Y543350I-500J-2D01*
G02X502847Y543405I-285J1475D01*
G03X501568Y542766I-327J-945D01*
G02X500629Y544645I-1430J459D01*
G03X501908Y545284I327J945D01*
G02X504804Y545150I1430J-459D01*
G03X505756Y544367I976J217D01*
G02X505855Y541369I-38J-1502D01*
G03X504948Y540318I91J-996D01*
G37*
G36*
G01X552133Y548293D02*
G02X550295Y548375I-972J-1145D01*
G03X550366Y549955I-576J817D01*
G02X552204Y549873I972J1145D01*
G03X552133Y548293I576J-817D01*
G37*
G36*
G01X502636Y551153D02*
G02X502059Y549037I702J-1328D01*
G03X500740Y549397I-852J-524D01*
G02X501317Y551513I-702J1328D01*
G03X502636Y551153I852J524D01*
G37*
G36*
G01X501297Y563981D02*
G02X499100Y564110I-1158J-956D01*
G03X499179Y565469I-692J722D01*
G02X499136Y567325I1159J955D01*
G03Y568525I-800J600D01*
G02X501540I1202J900D01*
G03Y567325I800J-600D01*
G02X501376Y565340I-1202J-900D01*
G03X501297Y563981I692J-722D01*
G37*
G36*
G01X552594Y569593D02*
G02X550302Y569378I-1056J-1068D01*
G03X550182Y570657I-823J568D01*
G02X552474Y570872I1056J1068D01*
G03X552594Y569593I823J-568D01*
G37*
G36*
G01X513321Y589675D02*
G02X513224Y592050I-967J1150D01*
G03X514446Y592100I579J815D01*
G02X514543Y589725I967J-1150D01*
G03X513321Y589675I-579J-815D01*
G37*
G36*
G01X563426Y502949D02*
G03X562736Y502891I-315J-389D01*
G02X562554Y505053I-1126J994D01*
G03X563244Y505111I315J389D01*
G02X563426Y502949I1126J-994D01*
G37*
G36*
G01X503171Y528126D02*
G03X502515Y528008I-262J-426D01*
G02X502118Y530211I-1184J924D01*
G03X502774Y530329I262J426D01*
G02X503171Y528126I1184J-924D01*
G37*
G36*
G01X529260Y540924D02*
G03X529884Y540824I373J333D01*
G02X529516Y538526I754J-1299D01*
G03X528892Y538626I-373J-333D01*
G02X527011Y538932I-754J1299D01*
G03X526312Y538982I-375J-331D01*
G02X526465Y541118I-974J1143D01*
G03X527164Y541068I375J331D01*
G02X529260Y540924I974J-1143D01*
G37*
G36*
G01X518019Y541613D02*
G03X518144Y542262I-306J395D01*
G02X520357Y541837I1294J763D01*
G03X520232Y541188I306J-395D01*
G02X518019Y541613I-1294J-763D01*
G37*
G36*
G01X498874Y586851D02*
G03X499142Y587970I-661J750D01*
G02X501532Y587399I1396J555D01*
G03X501264Y586280I661J-750D01*
G02X498874Y586851I-1396J-555D01*
G37*
G36*
G01X526578Y481330D02*
G02X524649Y481347I-975J-1143D01*
G03X524663Y482880I-635J772D01*
G02X526592Y482863I975J1143D01*
G03X526578Y481330I635J-772D01*
G37*
G36*
G01X606306Y237658D02*
G02X604442Y237154I-632J-1363D01*
G03X604042Y238632I-821J571D01*
G02X603585Y238961I634J1362D01*
G03X602066Y238881I-725J-688D01*
G02X599682I-1192J914D01*
G03X598163Y238961I-794J-608D01*
G02X597479Y238549I-1089J1034D01*
G03X596799Y237270I269J-963D01*
G02X594969Y238241I-1425J-475D01*
G03X595649Y239520I-269J963D01*
G02X598266Y240909I1425J475D01*
G03X599785Y240829I794J608D01*
G02X601963I1089J-1034D01*
G03X603482Y240909I725J688D01*
G02X605906Y239136I1192J-914D01*
G03X606306Y237658I821J-571D01*
G37*
G36*
G01X610927Y238853D02*
G02X608918Y237562I-512J-1412D01*
G03X608262Y238583I-997J81D01*
G02X610271Y239874I512J1412D01*
G03X610927Y238853I997J-81D01*
G37*
G36*
G01X593798Y248251D02*
G02X591928Y248258I-939J-1172D01*
G03X591934Y249823I-620J785D01*
G02X593804Y249816I939J1172D01*
G03X593798Y248251I620J-785D01*
G37*
G36*
G01X602045Y248854D02*
G02Y250736I-1171J941D01*
G03X603603I779J627D01*
G02X605825Y250868I1171J-941D01*
G03X607223I699J715D01*
G02Y248722I1051J-1073D01*
G03X605825I-699J-715D01*
G02X603603Y248854I-1051J1073D01*
G03X602045I-779J-627D01*
G37*
G36*
G01X592868Y263510D02*
G03X592916Y264203I-335J371D01*
G02X595073Y264053I1151J965D01*
G03X595025Y263360I335J-371D01*
G02X592868Y263510I-1151J-965D01*
G37*
G36*
G01X622994Y591342D02*
X622200Y592135D01*
Y613700D01*
X622994Y614494D01*
X644600D01*
X645558Y613535D01*
Y592259D01*
X644641Y591342D01*
X622994D01*
G37*
G36*
G01X667475Y384565D02*
G03X665524Y384705I-1163J-2547D01*
G03X663574Y384565I-787J-2687D01*
G01X663573D01*
X663276Y384429D01*
X646579D01*
X645336Y385672D01*
Y409535D01*
X646333Y410531D01*
X670526D01*
X671480Y409577D01*
Y385221D01*
X670689Y384429D01*
X667773D01*
X667476Y384565D01*
X667475D01*
G37*
G36*
G01X666369Y614641D02*
G02X665016Y616038I-1499J-98D01*
G03X666111Y617099I97J995D01*
G02X667464Y615702I1499J98D01*
G03X666369Y614641I-97J-995D01*
G37*
G54D30*
X109260Y648989D03*
Y644687D03*
X109500Y616724D03*
X109410Y621425D03*
X109640Y611890D03*
X184367Y337792D03*
X185195Y332852D03*
X186296Y326366D03*
X177029Y347811D03*
X168110Y350642D03*
X174876Y336549D03*
X177359Y332553D03*
X167383Y341306D03*
X166189Y335285D03*
X175330Y318552D03*
X178812Y324259D03*
X176037Y309845D03*
X164418Y348187D03*
X150510Y336306D03*
X150918Y318134D03*
X151230Y330164D03*
X161513Y317143D03*
X154581Y308767D03*
X161687Y310355D03*
X144058Y376025D03*
X145580Y316836D03*
X146100Y323543D03*
X145720Y311336D03*
X149020Y303498D03*
X197130Y626135D03*
X196907Y605012D03*
X197030Y598535D03*
X192130Y632235D03*
X184932Y619437D03*
X185032Y612937D03*
X184932Y600537D03*
X185032Y606737D03*
X167530Y631935D03*
X165832Y619437D03*
X178632D03*
X172532Y619537D03*
X165832Y613137D03*
Y606037D03*
Y600337D03*
X173432Y600437D03*
X179532D03*
X178416Y587849D03*
X162668Y631897D03*
X195420Y372406D03*
X202823Y376922D03*
X197938Y376839D03*
X200439Y390168D03*
X203880Y385272D03*
X200488Y396425D03*
X201267Y403294D03*
X254813Y427018D03*
X266822Y443297D03*
X316963Y467655D03*
X321357Y456709D03*
X321246Y472669D03*
X320080Y512736D03*
X318968Y536052D03*
X322986Y467109D03*
X325040Y480129D03*
X330115Y490303D03*
X335162Y502791D03*
X326740Y495763D03*
X329672Y502057D03*
X326170Y518386D03*
X335860Y516486D03*
X336010Y531598D03*
X329348Y533403D03*
X332408Y544097D03*
X348870Y501571D03*
X343420Y497966D03*
X340902Y503742D03*
X341512Y512429D03*
X346350Y517286D03*
X340182Y531787D03*
X341011Y537828D03*
X296913Y514460D03*
X285530Y573002D03*
X279658Y574443D03*
X276809Y471853D03*
X268009Y570953D03*
X263792Y574203D03*
X261175Y569054D03*
X274309Y574653D03*
X269609Y576413D03*
X249909Y568653D03*
X245609Y517182D03*
X246465Y464893D03*
X228604Y479682D03*
X234209Y480953D03*
X226255Y472579D03*
X218040Y473853D03*
X253490Y53736D03*
X240692Y344204D03*
X238084Y355992D03*
X237578Y369584D03*
X243078Y368384D03*
X244595Y363535D03*
X313222Y374229D03*
X309131Y374573D03*
X303171Y374224D03*
X281450Y373151D03*
X286550Y374402D03*
X277040Y376172D03*
X275497Y390758D03*
X260536Y374216D03*
X256588Y359005D03*
X259444Y354291D03*
X247789Y322910D03*
X262798Y417886D03*
X265532Y422648D03*
X277475Y695723D03*
X292970Y682450D03*
X322765Y327721D03*
X313980Y335813D03*
X314550Y331564D03*
X321130Y342418D03*
X319807Y346376D03*
X319288Y350376D03*
X333726Y353801D03*
X333440Y349221D03*
X381907Y21507D03*
X399002Y17519D03*
X397655Y21336D03*
X555938Y97292D03*
X551454Y97154D03*
X557995Y110244D03*
X548007Y139415D03*
X552173Y138528D03*
X550550Y151682D03*
X558059Y154254D03*
X558348Y142511D03*
X550604Y168072D03*
X550370Y157461D03*
X551395Y174172D03*
X558768Y191223D03*
X553909Y207401D03*
X547927Y212190D03*
X558416Y210682D03*
X547148Y220220D03*
X566090Y109136D03*
X560938Y97195D03*
X569559Y103123D03*
X563230Y150222D03*
X564076Y145372D03*
X563129Y178369D03*
X561909Y207393D03*
X578938Y103123D03*
X589308Y103990D03*
X583829Y117732D03*
X583661Y121836D03*
X580501Y138336D03*
X583829Y132232D03*
X583547Y128232D03*
X581565Y154969D03*
X583970Y144589D03*
X580180Y148894D03*
X579540Y143304D03*
X579897Y161355D03*
X584438Y160933D03*
X582792Y167632D03*
X581915Y179955D03*
X582920Y194220D03*
X588692Y192809D03*
X585580Y210516D03*
X598123Y102023D03*
X600118Y112568D03*
X592938Y133232D03*
X594938Y127893D03*
X592491Y175906D03*
X593277Y179955D03*
X436710Y446260D03*
X421770Y433187D03*
X422080Y410454D03*
X421710Y424527D03*
X406530Y440667D03*
X406150Y433203D03*
X406140Y424766D03*
X392076Y470970D03*
X398800Y462248D03*
X437120Y612933D03*
X435319Y600123D03*
X422221Y619873D03*
X431520Y607039D03*
X422210Y605343D03*
X429340Y596874D03*
X406100Y631851D03*
X547638Y462356D03*
X556971Y460656D03*
X556959Y443009D03*
X556771Y456156D03*
X540141Y442994D03*
X530038Y444323D03*
X535352Y440414D03*
X529968Y440216D03*
X536440Y431923D03*
X541440Y431787D03*
X512867Y443679D03*
X517929Y439676D03*
X506456Y446928D03*
X547488Y452373D03*
X546384Y445107D03*
X543381Y448428D03*
X551140Y445789D03*
X497818Y440265D03*
X591100Y450128D03*
X590720Y456076D03*
X588153Y459599D03*
X578830Y448192D03*
X589070Y423525D03*
X547000Y590163D03*
X550938Y587325D03*
X551438Y561225D03*
X545413Y547950D03*
X549920Y527242D03*
X554860Y531701D03*
X544138Y530125D03*
X548470Y378127D03*
X540701Y590162D03*
X527638Y590325D03*
X533038D03*
X534638Y539825D03*
X513838Y556925D03*
X513480Y541499D03*
X515110Y528785D03*
X500538Y600925D03*
X505738Y600425D03*
X500438Y574925D03*
X510338Y571325D03*
X500038Y555925D03*
X516353Y480708D03*
X547340Y484025D03*
X594174Y256695D03*
X596774Y249795D03*
X591707Y230162D03*
X581474Y274795D03*
X578076Y260093D03*
Y253393D03*
Y246693D03*
X585579Y230095D03*
X579707Y229395D03*
X564676Y253693D03*
Y260093D03*
X571476D03*
X564676Y246693D03*
X571576D03*
X569874Y231795D03*
X545703Y245725D03*
X550040Y243929D03*
X627084Y578257D03*
X651437Y578943D03*
X641870Y580743D03*
X646732Y580781D03*
X639673Y576888D03*
X646870Y576243D03*
X673368Y416621D03*
X669215Y377488D03*
X674235Y379364D03*
X712740Y593101D03*
X695600Y590788D03*
X670940Y612070D03*
X691148Y140140D03*
X691280Y149571D03*
X691314Y145071D03*
X701687Y212132D03*
X700947Y216868D03*
X700994Y221368D03*
G54D37*
X546000Y192000D03*
X544500Y197500D03*
G54D36*
X590999Y77041D03*
Y84915D03*
Y92789D03*
G54D35*
X546181Y81889D03*
G54D31*
X295047Y554565D03*
X288009Y495653D03*
G54D32*
X290322Y549841D03*
X290323Y502595D03*
X235307Y566357D03*
X243075Y552984D03*
Y508891D03*
G54D34*
X514780Y28803D03*
X524780D03*
X514780Y38803D03*
X524780D03*
X534780Y28803D03*
X544780D03*
X534780Y38803D03*
X544780D03*
X554780Y28803D03*
Y38803D03*
X577371Y28803D03*
X587371D03*
X577371Y38803D03*
X587371D03*
X597371Y28803D03*
Y38803D03*
G54D33*
X277725Y521493D03*
X261972Y562431D03*
X231209Y566282D03*
G54D28*
X45282Y338300D03*
Y321764D03*
G54D38*
X711575Y143555D03*
X733975D03*
X711575Y222361D03*
G54D29*
X25455Y356832D03*
%LPD*%
G75*
G36*
G01X623202Y613285D02*
X623409Y613492D01*
X644185D01*
X644557Y613120D01*
Y592674D01*
X644226Y592343D01*
X623409D01*
X623202Y592550D01*
Y613285D01*
G37*
G36*
G01X667990Y385431D02*
X667891Y385476D01*
G03X665524Y385737I-1579J-3458D01*
G03X663158Y385476I-787J-3719D01*
G01X663059Y385431D01*
X646994D01*
X646338Y386087D01*
Y409120D01*
X646748Y409530D01*
X670111D01*
X670479Y409162D01*
Y385636D01*
X670274Y385431D01*
X667990D01*
G37*
G54D10*
X23628Y321764D03*
Y338300D03*
G54D20*
G01X195126Y249955D02*
X195128Y249953D01*
X195948D01*
X200398Y245503D01*
Y243515D01*
X199303Y242420D01*
X197908D01*
X191380Y235892D01*
Y230885D01*
X185607Y225112D01*
X182721D01*
X181393Y223784D01*
G01X198685Y237385D02*
X194000Y232700D01*
Y231296D01*
X189920Y227216D01*
Y226397D01*
X186800Y223277D01*
X184926D01*
X184166Y222517D01*
G01X196860Y224622D02*
Y226982D01*
X202140Y232262D01*
Y235916D01*
X203338Y237114D01*
Y241269D01*
X205566Y243497D01*
G01X198296Y232699D02*
X198293Y232696D01*
X197985D01*
X192179Y226890D01*
Y225736D01*
X187359Y220916D01*
X187159D01*
G01X230199Y513607D02*
X231275D01*
G01X235199Y528033D02*
Y527223D01*
G01Y525305D02*
Y524070D01*
G01Y521982D02*
Y520930D01*
G01X180454Y536076D02*
X182037D01*
G01X238251Y528598D02*
X238355Y528494D01*
Y527178D01*
G01Y525231D02*
Y523945D01*
G01X232059Y543025D02*
Y543939D01*
G01X205535Y234497D02*
X205528Y234490D01*
Y231243D01*
X201820Y227535D01*
Y224307D01*
G01X199470Y224842D02*
Y227507D01*
X203508Y231545D01*
Y235153D01*
X205271Y236916D01*
Y240209D01*
G01X227070Y507324D02*
X227587D01*
G01X228908Y508543D02*
Y509528D01*
G01X230041Y516755D02*
X231401D01*
G01X233220D02*
X234055D01*
G01X235192Y515507D02*
Y514472D01*
G01X219904Y522853D02*
X222118Y525067D01*
X224248D01*
X224954Y524361D01*
X228557Y523060D01*
X230844D01*
X231275Y522838D01*
X231476Y522703D01*
X233626Y521489D01*
G01Y518339D02*
X232061Y519904D01*
X224460D01*
G01X169491Y529702D02*
X175105D01*
X178986Y529770D01*
G01X229813Y526210D02*
X231040D01*
G01X234078Y538802D02*
X233081D01*
G01X231326D02*
X230105D01*
G01X230219Y535662D02*
X231361D01*
G01X233235D02*
X234319D01*
G01X205535Y228682D02*
X204190Y227337D01*
Y223552D01*
G01X213600Y224555D02*
Y226824D01*
X211525Y228899D01*
X211089D01*
X210110Y229878D01*
Y231256D01*
X211218Y232364D01*
X213116D01*
X217135Y236383D01*
Y237385D01*
G01Y240785D02*
Y239770D01*
X217140D01*
X219150Y237760D01*
Y231558D01*
X221100Y229608D01*
Y227103D01*
G01X218600Y226631D02*
Y228750D01*
X217135Y230215D01*
Y230585D01*
G01X211935D02*
X213197D01*
X216100Y227682D01*
Y226599D01*
G01X226010Y240342D02*
X224310Y238642D01*
Y232428D01*
X225570Y231168D01*
Y230256D01*
G01X254418Y240407D02*
X255237Y239588D01*
Y235736D01*
X256587Y234386D01*
X259638D01*
X268160Y225864D01*
Y225138D01*
G01X265470Y224229D02*
Y225358D01*
X258077Y232751D01*
X255779D01*
X254181Y234349D01*
Y234521D01*
G01X257950Y236924D02*
X259842D01*
X269386Y227380D01*
X269963D01*
G01X260108Y240376D02*
X265530Y234954D01*
Y233948D01*
X269054Y230424D01*
X269486D01*
G01X276444Y270543D02*
X275646Y269745D01*
X275425D01*
X274218Y268538D01*
X271942D01*
X268866Y265462D01*
Y255473D01*
X271563Y252776D01*
Y251973D01*
X272503Y251033D01*
G01X273444Y270543D02*
X272865Y269964D01*
X272193D01*
X267049Y264820D01*
Y261534D01*
X265420Y259905D01*
Y253706D01*
X268475Y250651D01*
X269781D01*
X272035Y248397D01*
G01X303188Y256923D02*
X300967Y259144D01*
X294629D01*
X288149Y265624D01*
X285046D01*
X283362Y267308D01*
X279119D01*
X278321Y266510D01*
X274182D01*
X273521Y265849D01*
G01X288775Y258631D02*
X282834Y264572D01*
X281537D01*
X279913Y262948D01*
X275446D01*
X273849Y261351D01*
Y261349D01*
X272464Y259964D01*
G01X279444Y270543D02*
X278556Y269655D01*
X278554D01*
X276518Y267619D01*
X272336D01*
X270016Y265299D01*
Y256137D01*
X272841Y253312D01*
G01X280526Y252072D02*
X279400Y253198D01*
Y258555D01*
X278820Y259135D01*
X278811D01*
G01X304810Y259456D02*
X303918Y260348D01*
X294794D01*
X288488Y266654D01*
X286090D01*
X282309Y270435D01*
G01X279336Y264795D02*
X280336Y265795D01*
Y265797D01*
X283253D01*
X284454Y264596D01*
X287806D01*
X296831Y255571D01*
X301337D01*
X302056Y254852D01*
G54D11*
G01X58000Y412641D02*
X59140D01*
X73868Y397913D01*
G01X139310Y478102D02*
Y467065D01*
X119278Y447033D01*
Y427563D01*
X121248Y425593D01*
X129028D01*
G01X136420Y599352D02*
X138090Y597682D01*
Y566617D01*
X141240Y563467D01*
Y544509D01*
X151977Y533772D01*
Y531697D01*
X151266Y530986D01*
Y503620D01*
X157370Y497516D01*
X163667D01*
X187600Y473583D01*
Y471653D01*
X202012Y457241D01*
X297548D01*
X300040Y459733D01*
G01X140110Y675907D02*
X138090Y673887D01*
Y601022D01*
X136420Y599352D01*
G01X178982Y688631D02*
Y678582D01*
X171864Y671464D01*
X167035D01*
X164776Y669205D01*
X148200D01*
G01X178225Y290579D02*
X185807D01*
X186627Y291399D01*
X197649D01*
X199922Y293672D01*
Y297981D01*
X201299Y299358D01*
X202525D01*
G01X178982Y688631D02*
X172200Y695413D01*
Y714673D01*
X171200Y715673D01*
X171154D01*
G01X218899Y299998D02*
Y299242D01*
X220723Y297418D01*
X226664D01*
X227601Y298355D01*
Y313591D01*
X225444Y315748D01*
G01D02*
X225199D01*
G01X225237Y671772D02*
X228179Y674714D01*
X234380D01*
X237422Y671672D01*
X239168D01*
G01X252486Y671772D02*
X249356Y674902D01*
X241860D01*
X239168Y672210D01*
Y671672D01*
G01X263127Y674558D02*
X254290D01*
X252486Y672754D01*
Y671772D01*
G01X263127Y674558D02*
X261090Y676595D01*
Y694191D01*
X252131Y703150D01*
X250795D01*
G01X265913Y671772D02*
X263127Y674558D01*
G01X278350Y687309D02*
Y684647D01*
X286778Y676219D01*
X290401D01*
X296175Y670445D01*
X303005D01*
X306294Y667156D01*
G01X305213Y720393D02*
X309198D01*
X311990Y717601D01*
G01X320520Y375642D02*
Y389742D01*
X311460Y398802D01*
Y424384D01*
X309440Y426404D01*
G01X351810Y706800D02*
X327700D01*
X321820Y712680D01*
G01X311990Y717601D02*
X315480Y714111D01*
Y711920D01*
X317054Y710346D01*
X319486D01*
X321820Y712680D01*
G01X339750Y73383D02*
X348324Y81957D01*
X405227D01*
X419862Y96592D01*
Y118122D01*
X416740Y121244D01*
Y190067D01*
X448076Y221403D01*
Y235467D01*
X449230Y236621D01*
Y260380D01*
X452360Y263510D01*
Y277386D01*
X449290Y280456D01*
Y303689D01*
X423213Y329766D01*
X391889D01*
X390080Y331575D01*
G01X360350Y395873D02*
X348730Y407493D01*
Y422140D01*
X357650Y431060D01*
Y520942D01*
X355320Y523272D01*
Y539648D01*
X384294Y568622D01*
X388723D01*
X390000Y567345D01*
G01X367350Y713661D02*
X362749Y709060D01*
X357332D01*
X355072Y706800D01*
X351810D01*
G01X367350Y713661D02*
X369083D01*
X371170Y711574D01*
G01X484780Y314090D02*
X471623D01*
X434319Y351394D01*
X415228D01*
X395750Y370872D01*
Y391596D01*
X380180Y407166D01*
Y409238D01*
X381410Y410468D01*
Y434348D01*
X379875Y435883D01*
Y464996D01*
X378739Y466132D01*
Y468216D01*
X379790Y469267D01*
Y490615D01*
X381760Y492585D01*
Y496004D01*
G01X371170Y711574D02*
X373985Y708759D01*
X377227D01*
X379899Y711431D01*
X382960D01*
G01X416515Y547602D02*
X419860Y550947D01*
X430718D01*
X434203Y547462D01*
Y542897D01*
G01X442520Y223623D02*
X445270Y226373D01*
Y236753D01*
X446430Y237913D01*
Y263050D01*
X444560Y264920D01*
Y269317D01*
X444665Y269422D01*
Y282092D01*
X445890Y283317D01*
G01X434203Y542897D02*
X437131Y545825D01*
Y551855D01*
X441326Y556050D01*
G01X492260Y482826D02*
Y457635D01*
X489170Y454545D01*
Y435829D01*
X491480Y433519D01*
Y418416D01*
X478737Y405673D01*
X465073D01*
X463158Y403758D01*
Y389898D01*
X494850Y358206D01*
Y315733D01*
X13170Y372673D03*
X18340Y366452D03*
X13120Y375871D03*
X16010Y369168D03*
X21530Y368991D03*
X19450Y550297D03*
X20650Y546243D03*
X20350Y555807D03*
X18960Y572061D03*
X17876Y578422D03*
X16200Y566921D03*
X13510Y591939D03*
X14500Y601957D03*
X11980Y617956D03*
X15349Y614142D03*
X13807Y634826D03*
X9300Y631472D03*
X9240Y638699D03*
X36848Y25198D03*
X36588Y32278D03*
X38280Y362184D03*
X35750Y364593D03*
X33420Y367309D03*
X23860Y366275D03*
X23610Y568111D03*
X44010Y55170D03*
X40690Y359555D03*
X50870Y564008D03*
X53988Y568748D03*
X49680Y579709D03*
X49620Y574212D03*
X50270Y627793D03*
X48540Y624953D03*
X46890Y633564D03*
X58000Y412641D03*
X57710Y572918D03*
X57070Y580074D03*
X57440Y585607D03*
X62160Y644091D03*
X59390Y642906D03*
X56240Y630081D03*
X59530Y631704D03*
X66880Y761625D03*
X56500Y789667D03*
X73868Y397913D03*
X101449Y194368D03*
X98700Y234650D03*
X92422Y531081D03*
X95660Y531362D03*
X98803Y531597D03*
X97268Y537055D03*
X97366Y542897D03*
X98370Y619252D03*
X94070Y618986D03*
Y613841D03*
X97790Y613797D03*
X96200Y616325D03*
X95350Y644088D03*
X95310Y647481D03*
X98480Y646217D03*
X98410Y648878D03*
X89810Y765905D03*
X97390Y766435D03*
X111220Y160923D03*
X106090Y167615D03*
X112530Y186363D03*
X106760Y175370D03*
X114920Y179082D03*
X108910Y193194D03*
X110230Y360735D03*
Y363235D03*
X116370Y785941D03*
X104300Y773100D03*
X131068Y76588D03*
X126220Y80364D03*
Y83291D03*
X125480Y91163D03*
X132400Y88153D03*
X129580Y86837D03*
X129780Y92580D03*
X124150Y94643D03*
X128330Y98360D03*
X129028Y425593D03*
X132190Y662616D03*
X130260Y679836D03*
X132334Y732982D03*
X119900Y754021D03*
X125600Y759000D03*
X125960Y785699D03*
X120090Y780618D03*
X130850Y782456D03*
X118169Y783857D03*
X130660Y785601D03*
X127290Y781982D03*
X122720Y785051D03*
X135290Y87664D03*
X140350Y81347D03*
X147570Y249033D03*
X134540Y267786D03*
X139950Y293835D03*
X137889Y403348D03*
X141800Y404481D03*
X141847Y401820D03*
X135088Y405060D03*
X135181Y402121D03*
X145295Y404388D03*
X145284Y401507D03*
X138437Y435930D03*
Y438430D03*
X147576Y445279D03*
Y447779D03*
Y450279D03*
X138437Y440930D03*
X139310Y478102D03*
X136420Y599352D03*
X148200Y669205D03*
X140110Y675907D03*
X139158Y686725D03*
X135280Y679212D03*
X139600Y781281D03*
X135470Y781697D03*
X135610Y784521D03*
X139680Y784596D03*
X149450Y780429D03*
X149721Y292987D03*
X160710Y384044D03*
X162940Y406188D03*
X154370Y449930D03*
X162335Y512456D03*
X154140Y577815D03*
X150380Y602885D03*
X153422Y603043D03*
X163138Y778565D03*
X160480Y777583D03*
X155170Y780656D03*
X164630Y781222D03*
X153320Y783499D03*
X160320Y786346D03*
X149810Y783858D03*
X177733Y91967D03*
X177680Y101764D03*
X177763Y121057D03*
X178040Y228978D03*
X178929Y262244D03*
X180430Y392969D03*
X175663Y386424D03*
X180440Y398056D03*
X172760Y406540D03*
X168189Y514331D03*
X178085Y512456D03*
X173252Y515693D03*
X165707Y506156D03*
X172087Y510536D03*
X169615Y519216D03*
X169491Y529702D03*
X166837Y523486D03*
X174930Y547106D03*
X173163Y551903D03*
X167105Y552882D03*
X178083Y553402D03*
X166605Y587860D03*
X174479Y631986D03*
X177038Y647135D03*
X166388Y647435D03*
X171180Y652009D03*
X171270Y655650D03*
X178982Y688631D03*
X171154Y715673D03*
X175463Y720245D03*
X177920Y739302D03*
X169350Y785470D03*
X172600Y780150D03*
X169860Y782086D03*
X167350Y778074D03*
X194825Y10196D03*
X194861Y12952D03*
X184928Y91847D03*
X189928D03*
X196653Y91837D03*
X196493Y105637D03*
X183013Y98813D03*
X190100Y99701D03*
X184050Y230139D03*
X183550Y235060D03*
X188899Y240208D03*
X195126Y249955D03*
X184296Y241098D03*
X188899Y236808D03*
X192298Y286183D03*
X193500Y489796D03*
X181231Y512455D03*
X191457Y531553D03*
X186841Y545372D03*
X181232Y553402D03*
X181330Y587535D03*
X182353Y631612D03*
X188566Y722353D03*
X183566D03*
X193566Y722333D03*
X196079Y723943D03*
X204785Y13762D03*
X204978Y10605D03*
X201849Y15292D03*
X198577Y15374D03*
X205903Y101477D03*
X199993Y103637D03*
X205535Y234497D03*
Y228682D03*
X211935Y230585D03*
X198296Y232699D03*
X211935Y237385D03*
Y240785D03*
X205566Y243497D03*
X205271Y240209D03*
X198685Y237385D03*
Y244085D03*
X206319Y296863D03*
X202525Y299358D03*
X200211Y321446D03*
X200572Y323920D03*
X205790Y387003D03*
X210880Y402359D03*
X206380Y402201D03*
X211609Y516553D03*
X205257Y528822D03*
X205286Y551130D03*
X197230Y595335D03*
X198890Y584105D03*
X207178Y591595D03*
X208904Y611515D03*
X199786Y618893D03*
X197230Y615435D03*
X208904Y616515D03*
X200910Y659735D03*
X199510Y663158D03*
X205410Y661200D03*
X198566Y722353D03*
X209017Y722344D03*
X203611Y722303D03*
X222983Y91587D03*
X220983Y106174D03*
X228138Y125802D03*
X226010Y233542D03*
X217135Y230585D03*
X226010Y240342D03*
X217135Y240785D03*
Y237385D03*
X225973Y265197D03*
X215749Y293698D03*
Y287398D03*
X218899Y299998D03*
Y303148D03*
X218947Y312617D03*
X224949Y328707D03*
X225199Y315748D03*
X224585Y322992D03*
X224711Y325922D03*
X214786Y388603D03*
X218090Y390891D03*
X215120Y399654D03*
X214406Y395539D03*
X213710Y402237D03*
X228242Y463681D03*
X223953Y463550D03*
X212809Y479053D03*
X215409Y479253D03*
X219309Y489353D03*
X222209D03*
X217609Y516353D03*
X219328Y528823D03*
X223376Y523322D03*
X215946Y544202D03*
X225237Y671772D03*
X224060Y690317D03*
X224336Y687758D03*
X223707Y695436D03*
X220580Y692876D03*
X223741Y700554D03*
X221340Y697995D03*
X217530Y715305D03*
X221320Y720698D03*
X213310Y719064D03*
X222710Y713706D03*
X235113Y91307D03*
X231013Y91547D03*
X230643Y108497D03*
X234243Y100156D03*
X233083Y94817D03*
X237773Y103607D03*
X233138Y125802D03*
X232948Y234047D03*
X236710Y244042D03*
X242460Y237591D03*
X237654Y249719D03*
X241613Y262197D03*
X239569Y266639D03*
X237594Y252754D03*
X233793Y266697D03*
Y257697D03*
X241613Y268197D03*
X228821Y274197D03*
X231648Y274243D03*
X240949Y296848D03*
X237799Y303148D03*
X234649D03*
X237799Y306298D03*
X240949Y303148D03*
X240374Y328960D03*
X240511Y325517D03*
X236412Y387722D03*
X231223Y391424D03*
X239546Y390528D03*
X236430Y393470D03*
X235319Y464362D03*
X233309Y472553D03*
X237609Y472453D03*
X241909Y472553D03*
X239168Y671672D03*
X258103Y53688D03*
X257500Y56117D03*
X255287Y226709D03*
X254221Y230582D03*
X256492Y222466D03*
X254181Y234521D03*
X257950Y236924D03*
X254418Y240407D03*
X247389Y262139D03*
Y268139D03*
X244118Y303187D03*
X247025Y330512D03*
X247065Y385398D03*
X244546Y385315D03*
X247797Y406029D03*
X250297D03*
X252797D03*
X245297D03*
X255509Y472253D03*
X246109Y472465D03*
X251309Y472553D03*
X252036Y582131D03*
X252486Y671772D03*
X250795Y703150D03*
X259170Y705138D03*
X258570Y722981D03*
X248770Y724631D03*
X272245Y89585D03*
X271133Y92787D03*
X273973Y97645D03*
X260108Y240376D03*
X273521Y265849D03*
X272464Y259964D03*
X273444Y270543D03*
X274944Y278363D03*
X270386Y280407D03*
X267386D03*
X265825Y293987D03*
X268867Y293942D03*
X270444Y286183D03*
X265768Y287546D03*
X273444Y286183D03*
X273618Y295387D03*
X268944Y309643D03*
X265944Y309640D03*
X262700Y325494D03*
X269456Y355353D03*
X261539Y387755D03*
X263419Y393450D03*
X271720Y422587D03*
X269630Y424884D03*
X274180Y424966D03*
X275256Y445753D03*
X271035Y443051D03*
X273735Y443034D03*
X273509Y471649D03*
X260609Y472453D03*
X264909Y472553D03*
X269109Y472353D03*
X275452Y483219D03*
X268717Y606015D03*
X261967Y608638D03*
Y605638D03*
X260064Y602993D03*
X261967Y614638D03*
X263467Y626638D03*
X269428Y622966D03*
X261967Y617638D03*
X263467Y623638D03*
X273938Y633084D03*
X273674Y640095D03*
X273548Y636471D03*
X265913Y671772D03*
X272460Y687889D03*
X272650Y693742D03*
X269410Y706003D03*
X264600Y723086D03*
X277472Y34959D03*
Y37459D03*
X280072Y34330D03*
X275766Y52772D03*
X275800Y50212D03*
X276603Y92119D03*
X287423Y91857D03*
X281200Y98369D03*
X289720Y96094D03*
X278760Y101061D03*
X282166Y262922D03*
X281945Y260231D03*
X278811Y259135D03*
X279336Y264795D03*
X276444Y270543D03*
X282309Y270435D03*
X279444Y270543D03*
X277944Y278363D03*
X279386Y280407D03*
X276386D03*
X281767Y277742D03*
X281818Y290787D03*
X278918Y286887D03*
X276444Y286183D03*
X281859Y310862D03*
X286071Y329184D03*
X278067Y325842D03*
X282167Y324242D03*
X276400Y422341D03*
X280010Y422279D03*
X281190Y424966D03*
X278080Y424760D03*
X286210Y444926D03*
X289630Y444828D03*
X283212Y442286D03*
X286100Y442298D03*
X288742Y442090D03*
X287970Y446705D03*
X282000Y444966D03*
X279112Y444954D03*
X276626Y442913D03*
X279990Y442071D03*
X278350Y687309D03*
X275560Y697804D03*
X279060Y693306D03*
X275880Y722141D03*
X285880Y722268D03*
X284020Y724956D03*
X301870Y92072D03*
X296870D03*
X291927Y102991D03*
X293505Y94965D03*
X296927Y102991D03*
X303220Y98397D03*
X302930Y132994D03*
X301795Y310398D03*
X305250Y310342D03*
X300201Y300874D03*
X303197Y304297D03*
X305880Y339046D03*
X291860Y442927D03*
X292170Y445986D03*
X301240Y470885D03*
X300040Y459733D03*
X306220Y477125D03*
X304410Y572782D03*
X303110Y639381D03*
X306294Y667156D03*
Y675156D03*
Y671156D03*
X294120Y668391D03*
X306294Y679156D03*
X293286Y703504D03*
X305990Y697189D03*
X305213Y720393D03*
X293480Y725080D03*
X315083Y90207D03*
X311553Y92347D03*
X320740Y98599D03*
X312223Y96407D03*
X317970Y95961D03*
X307204Y304212D03*
X309190Y336959D03*
X321150Y357730D03*
X322255Y371935D03*
X321297Y367739D03*
X319363Y372149D03*
X311610Y432528D03*
X313530Y436460D03*
X315940Y438104D03*
X322599Y432505D03*
X309440Y426404D03*
X307800Y467859D03*
X310380Y473942D03*
X315980Y472128D03*
X307670Y473605D03*
X310453Y642451D03*
X313230Y702465D03*
X321820Y712680D03*
X311990Y717601D03*
X336495Y290569D03*
X333540Y315590D03*
X332700Y333089D03*
X324940Y413899D03*
X326190Y448621D03*
X329120Y449203D03*
X327780Y445819D03*
X331360Y447306D03*
X330388Y565803D03*
X332388Y567703D03*
X328088Y567503D03*
X335610Y658177D03*
X332747Y655636D03*
X332190Y659883D03*
X334640Y725035D03*
X353060Y61504D03*
X339750Y73383D03*
X345463Y90837D03*
X353713Y93057D03*
X344873Y94847D03*
X340450Y101914D03*
X343743Y120967D03*
X351503Y130972D03*
Y127972D03*
X341910Y325739D03*
X344720D03*
X343880Y356989D03*
X349110Y375767D03*
X352420Y375672D03*
X343770Y382166D03*
X345270Y452745D03*
X346750Y466532D03*
X338762Y479636D03*
X339506Y482841D03*
X348220Y486484D03*
X352160Y502138D03*
X351250Y499752D03*
X353400Y507260D03*
X353460Y504536D03*
X348190Y511550D03*
X353120Y510003D03*
X340330Y541931D03*
X342190Y565848D03*
X340340Y638054D03*
X345580Y638109D03*
X351730Y649206D03*
X353260Y688757D03*
X351810Y706800D03*
X339750Y695271D03*
X339010Y700406D03*
X338926Y697752D03*
X352010Y713968D03*
X365670Y64458D03*
X358343Y90948D03*
X354448Y108092D03*
X365283Y128125D03*
X354690Y377000D03*
X364645Y377065D03*
X364880Y384455D03*
X360350Y395873D03*
X365850Y414874D03*
X367496Y690248D03*
X367614Y693053D03*
X367520Y701710D03*
X367350Y713661D03*
X371180Y17789D03*
X370960Y20577D03*
X383247Y64141D03*
X373560Y63973D03*
X379560Y374955D03*
X379720Y372257D03*
X382620Y391882D03*
X379300Y380862D03*
X379286Y378015D03*
X379750Y383965D03*
X382190Y388077D03*
X376600Y408045D03*
X371260Y412879D03*
X383750Y437058D03*
X378910Y430874D03*
X381760Y496004D03*
X376540Y498385D03*
X371170Y711574D03*
X382960Y711431D03*
X372110Y720308D03*
X376770Y734898D03*
X392250Y59899D03*
X389690Y60665D03*
X401310Y61439D03*
X399598Y260251D03*
X398258Y252341D03*
X394378Y260501D03*
X399608Y275211D03*
X393458Y282931D03*
X392508Y275581D03*
X398038Y292571D03*
X399880Y319568D03*
X390080Y331575D03*
X389740Y404725D03*
X395740Y407528D03*
X393370Y411618D03*
X387080Y486400D03*
X385940Y482478D03*
X388890Y480439D03*
X386410Y477576D03*
X389670Y477262D03*
X388982Y496939D03*
X396590Y549310D03*
X399590Y553502D03*
X390000Y567345D03*
X401091Y587054D03*
X398386Y587126D03*
X401422Y597270D03*
Y599770D03*
X398822Y600399D03*
X395701Y637430D03*
X399440Y637340D03*
X392080Y692796D03*
X396150Y708926D03*
X394840Y711437D03*
X404738Y260421D03*
X402948Y253251D03*
X401618Y267351D03*
X403148Y270191D03*
X403628Y292201D03*
X408790Y317049D03*
X411240Y316482D03*
X406352Y471405D03*
X409054Y483084D03*
X412260Y482881D03*
X411439Y516956D03*
X402458Y505903D03*
X401556Y508937D03*
X416515Y547602D03*
X409520Y637387D03*
X414760Y636225D03*
X412080Y719034D03*
X414080Y721334D03*
X428405Y245194D03*
X424961Y241203D03*
X418905Y245694D03*
X426992Y250016D03*
X426335Y267062D03*
X421728Y279141D03*
X428748Y275222D03*
X418588Y286681D03*
X421128Y292601D03*
X423178Y284601D03*
X427909Y286759D03*
X427468Y292287D03*
X424904Y586283D03*
X425151Y608429D03*
X420245Y636004D03*
X417422Y637592D03*
X429820Y656709D03*
X420290Y733741D03*
X423900Y736055D03*
X442380Y75513D03*
X442520Y223623D03*
X441580Y250730D03*
X445890Y283317D03*
X438340Y403375D03*
X439150Y400930D03*
X443240Y401984D03*
X446830Y400551D03*
X445900Y403460D03*
X437887Y471073D03*
X442763Y549595D03*
X434203Y542897D03*
X441326Y556050D03*
X445604Y629045D03*
X442650Y719485D03*
X446260Y722014D03*
X458120Y44721D03*
X464170Y56436D03*
X455292Y162797D03*
X455470Y166963D03*
X452669Y157140D03*
X455913Y178698D03*
X450650Y203785D03*
X448970Y403846D03*
X451950Y402434D03*
X452895Y510061D03*
X453917Y550069D03*
X453854Y555069D03*
X464050Y633877D03*
X463020Y661023D03*
X464330Y663251D03*
X460822Y712620D03*
X451820Y712210D03*
X454070Y714226D03*
X475310Y59746D03*
X475030Y63879D03*
X479450Y63721D03*
X480220Y185766D03*
X464810Y311253D03*
X470090Y332824D03*
X475190Y339013D03*
X465913Y402659D03*
X465883Y399834D03*
X468810Y652180D03*
X477710Y722299D03*
X466620Y714137D03*
X473940Y714184D03*
X486810Y60785D03*
X483240Y60546D03*
X482500Y184169D03*
X487080Y180918D03*
X484780Y314090D03*
X494850Y315733D03*
X480830Y333921D03*
X495500Y447465D03*
X492260Y482826D03*
X494980Y482979D03*
X487832Y624429D03*
X490040Y622140D03*
X480310Y642224D03*
X493020Y646701D03*
X490120Y662703D03*
X509710Y127269D03*
X510000Y173500D03*
X506234Y207368D03*
X504941Y227859D03*
X509140Y338005D03*
X499551Y429636D03*
X505843Y465018D03*
X504613Y525200D03*
X500138Y558625D03*
X500419Y578644D03*
X500538Y572025D03*
X505738Y590525D03*
X504980Y616425D03*
X508400Y617803D03*
X501120Y633249D03*
X510700Y634300D03*
X496690Y633589D03*
X513120Y72069D03*
X518640Y125539D03*
X515600Y172800D03*
X521320Y178184D03*
X525293Y191705D03*
X520068Y207142D03*
X516551Y214987D03*
X524405Y212531D03*
X514766Y208222D03*
X514400Y340829D03*
X520510Y337299D03*
X527438Y340353D03*
X517617Y422944D03*
X526440Y422428D03*
X527300Y417368D03*
X523667Y438452D03*
X522379Y431974D03*
X513140Y452621D03*
X519440Y452321D03*
X526340D03*
X516353Y443517D03*
X523838Y442723D03*
X513140Y459721D03*
Y466021D03*
X525640Y473021D03*
X519640D03*
X513140D03*
X519938Y493125D03*
X524938D03*
X521938Y540325D03*
X516380Y540364D03*
X516738Y562425D03*
X513738D03*
X524638Y590225D03*
X520228Y590335D03*
X523800Y611145D03*
X520370Y625158D03*
X517888Y687901D03*
X518947Y685122D03*
X527111Y686052D03*
X542180Y93534D03*
X542700Y112881D03*
X538655Y151415D03*
X542002Y180100D03*
X541657Y207645D03*
X532320Y209470D03*
X528105Y230594D03*
X539267Y267102D03*
X541380Y340358D03*
X543110Y333848D03*
X536180Y341432D03*
X536170Y336603D03*
X531795Y340409D03*
X531430Y337074D03*
X527603Y337208D03*
X540700Y418852D03*
X541650Y422280D03*
X536440Y421973D03*
X533040Y453221D03*
X534738Y445523D03*
X541838Y450723D03*
X533740Y458021D03*
Y465021D03*
Y473021D03*
X543280Y491040D03*
X541538Y529625D03*
X534401Y529562D03*
X535776Y590487D03*
X530338Y590325D03*
X532420Y615484D03*
X530779Y637354D03*
X539830Y667332D03*
X531599Y689838D03*
X533270Y679351D03*
X531597Y697509D03*
X547480Y96632D03*
X546306Y110193D03*
X550490Y112989D03*
X555836Y179259D03*
X546000Y180000D03*
X549909Y207060D03*
X557909Y207537D03*
X555750Y212029D03*
X544500Y207000D03*
X545424Y226722D03*
X550090Y247079D03*
X545116Y266847D03*
X547929Y258102D03*
X557222Y285109D03*
X553690Y340829D03*
X547340Y339103D03*
X544500Y422583D03*
X557017Y438968D03*
X549574Y432582D03*
X555140Y445940D03*
X554550Y469674D03*
X545513Y469740D03*
X543338Y459323D03*
X546250Y490302D03*
X551538Y540325D03*
X551338Y544225D03*
X551438Y563825D03*
X551238Y584025D03*
X543850Y590313D03*
X552849Y631652D03*
X543400Y635615D03*
X550535Y721903D03*
X557488Y713709D03*
X553725Y717251D03*
X550004Y709559D03*
X555062Y708679D03*
X553193Y724847D03*
X546566Y724119D03*
X557426Y724436D03*
X565938Y96820D03*
X569682Y195199D03*
X572782D03*
X572690Y226569D03*
X572020Y222393D03*
X567980Y222353D03*
X568410Y226647D03*
X561258Y230153D03*
X566248Y230283D03*
X563506Y232027D03*
X566774Y275195D03*
X560865Y285434D03*
X565977Y456156D03*
X566059Y460956D03*
X571650Y625998D03*
X574730Y625521D03*
X565168Y674614D03*
Y669614D03*
X563577Y692284D03*
X565168Y689614D03*
Y694614D03*
X564319Y721587D03*
X562540Y713454D03*
X560062Y708679D03*
X566798Y734023D03*
X587968Y138765D03*
X576105Y231626D03*
X583853Y313783D03*
X579168Y313641D03*
X579788Y354743D03*
X575038Y554725D03*
X575138Y559825D03*
X577000Y620029D03*
X588950Y650070D03*
X583930Y652439D03*
X576846Y675985D03*
X578030Y690236D03*
X577010Y682718D03*
X576519Y687665D03*
X589500Y690546D03*
X585400Y697289D03*
X585693Y722428D03*
X583440Y724927D03*
X577570Y734118D03*
X593537Y161023D03*
X592917Y171906D03*
X593459Y240780D03*
X590874Y275195D03*
X598551Y329541D03*
X601450Y326509D03*
X600770Y358702D03*
X594860Y395088D03*
X600680Y412780D03*
X598670Y508170D03*
X606300Y551844D03*
X604820Y555040D03*
X605521Y601097D03*
X605010Y641435D03*
X600980Y641533D03*
X591279Y656223D03*
X596998Y658008D03*
X591840Y659568D03*
X596470Y655231D03*
X597300Y663128D03*
X604220Y703774D03*
X592960Y703291D03*
X601813Y715579D03*
X598880Y719232D03*
X611050Y423087D03*
X611130Y417928D03*
X616320Y537066D03*
X610070Y557588D03*
X611254Y617943D03*
X616730Y633290D03*
X608310Y641603D03*
X620510Y639427D03*
X607380Y699671D03*
X637738Y392034D03*
X633633Y403717D03*
X637614Y397259D03*
X635840Y449890D03*
X630570Y451450D03*
X622100Y465822D03*
X625900Y461769D03*
X632680Y466669D03*
X636010Y469995D03*
X634530Y521565D03*
X634921Y580163D03*
X627047Y581066D03*
X636868Y593141D03*
X630768Y593241D03*
X624468D03*
Y612141D03*
X624368Y605941D03*
Y599741D03*
X629868Y612241D03*
X635968D03*
X627986Y625895D03*
X622510Y635544D03*
X623290Y641222D03*
X631930Y655254D03*
X636170Y729335D03*
X647440Y386383D03*
X647340Y393283D03*
X647440Y408383D03*
X647340Y400083D03*
X641690Y443656D03*
X638350Y507893D03*
X646460Y512967D03*
X652690Y531693D03*
X640470Y523266D03*
X645040Y524444D03*
X645150Y535704D03*
X638166Y560972D03*
X638286Y557415D03*
X643568Y593241D03*
Y612341D03*
Y606641D03*
Y599541D03*
X642795Y624818D03*
X639940Y687841D03*
X655122Y315070D03*
X666270Y359134D03*
X659543Y377086D03*
X654340Y386283D03*
X661140D03*
X654840Y408483D03*
X661940Y408383D03*
X658295Y417662D03*
X653649Y417582D03*
X668779Y417135D03*
X664450Y435739D03*
X667774Y477992D03*
X655978Y609635D03*
X663560Y625019D03*
X659600Y623785D03*
X655610Y706309D03*
X659200Y721454D03*
X657570Y730414D03*
X658860Y727383D03*
X656000Y732400D03*
X680220Y200725D03*
X678650Y203480D03*
X681770Y203514D03*
X680310Y217357D03*
X678750Y214908D03*
X681870Y214942D03*
X679590Y352829D03*
X679430Y350013D03*
X669540Y386283D03*
X677946Y387211D03*
X669440Y395183D03*
Y408483D03*
X669540Y402783D03*
X679138Y397985D03*
X680017Y403143D03*
X683112Y479786D03*
X680790Y504521D03*
X675100Y749300D03*
X672710Y746235D03*
X672500Y749179D03*
X698150Y136791D03*
X687546Y154228D03*
X699990Y149631D03*
X700060Y144981D03*
X689820Y200159D03*
Y203491D03*
X691970Y216820D03*
X691690Y212100D03*
X693540Y205721D03*
X697800Y205879D03*
X692010Y221158D03*
X687584Y233034D03*
X687130Y464132D03*
X692520Y506898D03*
X699600Y776000D03*
X701770Y331938D03*
X702730Y455483D03*
X713300Y578995D03*
X713190Y583032D03*
X704000Y770800D03*
X719800Y24920D03*
X726500Y123466D03*
X726400Y130303D03*
X726470Y126659D03*
X731340Y476723D03*
X730800Y728400D03*
X729500Y746300D03*
X738370Y123395D03*
X738270Y130232D03*
X738340Y126588D03*
X747080Y129815D03*
X747600Y323527D03*
X745220Y327250D03*
X738130Y502748D03*
X732817Y489435D03*
X754580Y124020D03*
X754610Y127247D03*
X750930Y129815D03*
X750430Y314330D03*
X750350Y311343D03*
X750700Y323771D03*
X753230Y328262D03*
X759400Y334839D03*
X754850Y335055D03*
X755500Y337791D03*
X758500Y469500D03*
X765250Y357789D03*
X765610Y361194D03*
G54D21*
G01X208904Y611515D02*
X206979Y613440D01*
X206002D01*
X204660Y614782D01*
Y623466D01*
X211150Y629956D01*
Y639882D01*
X218043Y646775D01*
X242388D01*
X247238Y651625D01*
X261914D01*
X266537Y647002D01*
X281031D01*
X298989Y629044D01*
X309189D01*
X311150Y631005D01*
X316357D01*
X319161Y628201D01*
X330437D01*
X332920Y625718D01*
Y595113D01*
X350290Y577743D01*
X458391D01*
X468990Y567144D01*
Y549379D01*
X517160Y501209D01*
X520120D01*
X523010Y498319D01*
Y497054D01*
X523013Y497051D01*
Y494053D01*
X523941Y493125D01*
X524938D01*
G01X208904Y616515D02*
X206979Y614590D01*
X206479D01*
X205810Y615259D01*
Y622989D01*
X212300Y629479D01*
Y639405D01*
X218520Y645625D01*
X242865D01*
X247715Y650475D01*
X261437D01*
X266060Y645852D01*
X280554D01*
X298512Y627894D01*
X309666D01*
X311627Y629855D01*
X315880D01*
X318684Y627051D01*
X329960D01*
X331770Y625241D01*
Y594636D01*
X349813Y576593D01*
X457914D01*
X467840Y566667D01*
Y548902D01*
X469297Y547445D01*
Y546641D01*
X470358Y545580D01*
X471162D01*
X472223Y544519D01*
Y543715D01*
X473284Y542654D01*
X474088D01*
X477557Y539185D01*
Y538475D01*
X478618Y537414D01*
X479328D01*
X480389Y536353D01*
Y535643D01*
X481450Y534582D01*
X482160D01*
X483221Y533521D01*
Y532811D01*
X484282Y531750D01*
X484992D01*
X486053Y530689D01*
Y529979D01*
X487114Y528918D01*
X487824D01*
X488885Y527857D01*
Y527147D01*
X489946Y526086D01*
X490656D01*
X491717Y525025D01*
Y524315D01*
X492778Y523254D01*
X493488D01*
X494549Y522193D01*
Y521483D01*
X495610Y520422D01*
X496320D01*
X497381Y519361D01*
Y518651D01*
X498442Y517590D01*
X499152D01*
X500213Y516529D01*
Y515819D01*
X501274Y514758D01*
X501984D01*
X503045Y513697D01*
Y512987D01*
X504106Y511926D01*
X504816D01*
X505877Y510865D01*
Y510155D01*
X506938Y509094D01*
X507648D01*
X516683Y500059D01*
X519643D01*
X521860Y497842D01*
Y496577D01*
X521863Y496574D01*
Y493958D01*
X521030Y493125D01*
X519938D01*
G54D12*
X73740Y20708D03*
G54D22*
G01X178099Y550267D02*
X178700Y550868D01*
X179494D01*
X181819Y548543D01*
X190194D01*
X191464Y549813D01*
Y554958D01*
X192096Y555590D01*
X193092D01*
X193874Y554808D01*
Y550240D01*
X195877Y548237D01*
X202938D01*
X204320Y549619D01*
Y550164D01*
X205286Y551130D01*
G01X178083Y553402D02*
Y552867D01*
X178672Y552278D01*
X180079D01*
X182404Y549953D01*
X183709D01*
X184169Y550413D01*
X185549D01*
X186009Y549953D01*
X186709D01*
X187009Y550253D01*
X188309D01*
X188609Y549953D01*
X189609D01*
X190054Y550398D01*
Y552105D01*
X189594Y552564D01*
Y553724D01*
X190054Y554183D01*
Y555543D01*
X191511Y557000D01*
X193677D01*
X195284Y555393D01*
Y553853D01*
X195744Y553394D01*
Y552212D01*
X195284Y551753D01*
Y550825D01*
X196462Y549647D01*
X202353D01*
X202888Y550182D01*
Y550727D01*
X202486Y551130D01*
G54D13*
X159196Y515612D03*
X159179Y521893D03*
X162335Y521906D03*
X159180Y528227D03*
X162336Y550253D03*
X168617Y525756D03*
X172371Y519783D03*
X178099Y550267D03*
X181232Y515607D03*
X202486Y551130D03*
X218751Y543835D03*
X233626Y502591D03*
X236776Y518339D03*
X233626Y508891D03*
Y515190D03*
X230476D03*
X233626Y518339D03*
X230476D03*
Y512040D03*
X233626D03*
Y521489D03*
X236776D03*
X233626Y524639D03*
X230476D03*
Y527788D03*
Y521489D03*
X239925Y540386D03*
Y543536D03*
X236776Y540386D03*
Y537236D03*
X230476Y540386D03*
X233626D03*
X255673Y512040D03*
X252524D03*
Y549835D03*
X255673D03*
X262904Y293850D03*
X268943Y291086D03*
X268272Y512040D03*
X271422D03*
X268272Y549836D03*
X271421D03*
X277725Y534092D03*
Y527792D03*
Y540391D03*
Y543541D03*
Y537241D03*
X679175Y464038D03*
X683112D03*
Y483723D03*
Y487660D03*
X710671Y471913D03*
X702585Y483749D03*
X706734Y479786D03*
G54D23*
G01X38493Y-241864D02*
Y-246864D01*
G01X37036Y-241864D02*
X39950D01*
G01X44860Y-246864D02*
X42326D01*
Y-241864D01*
X44860D01*
G01X43846Y-244281D02*
X42326D01*
G01X47426Y-241864D02*
Y-246864D01*
X49960D01*
G01X53793Y-247031D02*
X53666Y-246947D01*
Y-246781D01*
X53793Y-246697D01*
X53920Y-246781D01*
Y-246947D01*
X53793Y-247031D01*
G01Y-244781D02*
X53666Y-244697D01*
Y-244531D01*
X53793Y-244447D01*
X53920Y-244531D01*
Y-244697D01*
X53793Y-244781D01*
G01X58576Y-248531D02*
X57943Y-247697D01*
X57626Y-246864D01*
Y-243531D01*
X57943Y-242697D01*
X58576Y-241864D01*
G01X63993D02*
X63486Y-242031D01*
X63106Y-242447D01*
X62853Y-242947D01*
X62663Y-243614D01*
X62600Y-244364D01*
X62663Y-245114D01*
X62853Y-245781D01*
X63106Y-246281D01*
X63486Y-246697D01*
X63993Y-246864D01*
X64500Y-246697D01*
X64880Y-246281D01*
X65133Y-245781D01*
X65323Y-245114D01*
X65386Y-244364D01*
X65323Y-243614D01*
X65133Y-242947D01*
X64880Y-242447D01*
X64500Y-242031D01*
X63993Y-241864D01*
G01X67700Y-245864D02*
X68080Y-246447D01*
X68586Y-246781D01*
X69156Y-246864D01*
X69663Y-246781D01*
X70170Y-246364D01*
X70486Y-245864D01*
X70550Y-245364D01*
X70423Y-244781D01*
X69980Y-244364D01*
X69536Y-244197D01*
X68966D01*
G01X69536D02*
X69916Y-243947D01*
X70233Y-243531D01*
X70360Y-243031D01*
X70233Y-242531D01*
X69916Y-242114D01*
X69346Y-241864D01*
X68776Y-241947D01*
X68206Y-242281D01*
G01X74510Y-248531D02*
X75143Y-247697D01*
X75460Y-246864D01*
Y-243531D01*
X75143Y-242697D01*
X74510Y-241864D01*
G01X77900Y-245864D02*
X78280Y-246447D01*
X78786Y-246781D01*
X79356Y-246864D01*
X79863Y-246781D01*
X80370Y-246364D01*
X80686Y-245864D01*
X80750Y-245364D01*
X80623Y-244781D01*
X80180Y-244364D01*
X79736Y-244197D01*
X79166D01*
G01X79736D02*
X80116Y-243947D01*
X80433Y-243531D01*
X80560Y-243031D01*
X80433Y-242531D01*
X80116Y-242114D01*
X79546Y-241864D01*
X78976Y-241947D01*
X78406Y-242281D01*
G01X83190Y-242697D02*
X83570Y-242197D01*
X84013Y-241947D01*
X84520Y-241864D01*
X85153Y-242031D01*
X85596Y-242447D01*
X85723Y-242947D01*
X85660Y-243447D01*
X85406Y-243864D01*
X84140Y-244697D01*
X83570Y-245281D01*
X83190Y-246114D01*
X83063Y-246864D01*
X85723D01*
G01X89366D02*
X89493Y-245781D01*
X89683Y-244864D01*
X89936Y-244031D01*
X90253Y-243114D01*
X90760Y-241864D01*
X88226D01*
G01X93770Y-245197D02*
X95416D01*
G01X98490Y-242697D02*
X98870Y-242197D01*
X99313Y-241947D01*
X99820Y-241864D01*
X100453Y-242031D01*
X100896Y-242447D01*
X101023Y-242947D01*
X100960Y-243447D01*
X100706Y-243864D01*
X99440Y-244697D01*
X98870Y-245281D01*
X98490Y-246114D01*
X98363Y-246864D01*
X101023D01*
G01X103400Y-245864D02*
X103780Y-246447D01*
X104286Y-246781D01*
X104856Y-246864D01*
X105363Y-246781D01*
X105870Y-246364D01*
X106186Y-245864D01*
X106250Y-245364D01*
X106123Y-244781D01*
X105680Y-244364D01*
X105236Y-244197D01*
X104666D01*
G01X105236D02*
X105616Y-243947D01*
X105933Y-243531D01*
X106060Y-243031D01*
X105933Y-242531D01*
X105616Y-242114D01*
X105046Y-241864D01*
X104476Y-241947D01*
X103906Y-242281D01*
G01X110653Y-246864D02*
Y-241864D01*
X108310Y-245447D01*
X111476D01*
G01X113600Y-246114D02*
X113980Y-246531D01*
X114423Y-246781D01*
X114993Y-246864D01*
X115563Y-246697D01*
X116006Y-246364D01*
X116323Y-245781D01*
X116386Y-245114D01*
X116260Y-244447D01*
X115943Y-244031D01*
X115500Y-243697D01*
X115056Y-243614D01*
X114613Y-243697D01*
X114043Y-244031D01*
X114233Y-241864D01*
X115943D01*
G01X123990Y-246864D02*
Y-241864D01*
X126396D01*
G01X125510Y-244281D02*
X123990D01*
G01X128710Y-246864D02*
X130293Y-241864D01*
X131876Y-246864D01*
G01X131306Y-245114D02*
X129280D01*
G01X134063Y-246864D02*
X136723Y-241864D01*
G01X134063D02*
X136723Y-246864D01*
G01X140493Y-247031D02*
X140366Y-246947D01*
Y-246781D01*
X140493Y-246697D01*
X140620Y-246781D01*
Y-246947D01*
X140493Y-247031D01*
G01Y-244781D02*
X140366Y-244697D01*
Y-244531D01*
X140493Y-244447D01*
X140620Y-244531D01*
Y-244697D01*
X140493Y-244781D01*
G01X145276Y-248531D02*
X144643Y-247697D01*
X144326Y-246864D01*
Y-243531D01*
X144643Y-242697D01*
X145276Y-241864D01*
G01X150693D02*
X150186Y-242031D01*
X149806Y-242447D01*
X149553Y-242947D01*
X149363Y-243614D01*
X149300Y-244364D01*
X149363Y-245114D01*
X149553Y-245781D01*
X149806Y-246281D01*
X150186Y-246697D01*
X150693Y-246864D01*
X151200Y-246697D01*
X151580Y-246281D01*
X151833Y-245781D01*
X152023Y-245114D01*
X152086Y-244364D01*
X152023Y-243614D01*
X151833Y-242947D01*
X151580Y-242447D01*
X151200Y-242031D01*
X150693Y-241864D01*
G01X154400Y-245864D02*
X154780Y-246447D01*
X155286Y-246781D01*
X155856Y-246864D01*
X156363Y-246781D01*
X156870Y-246364D01*
X157186Y-245864D01*
X157250Y-245364D01*
X157123Y-244781D01*
X156680Y-244364D01*
X156236Y-244197D01*
X155666D01*
G01X156236D02*
X156616Y-243947D01*
X156933Y-243531D01*
X157060Y-243031D01*
X156933Y-242531D01*
X156616Y-242114D01*
X156046Y-241864D01*
X155476Y-241947D01*
X154906Y-242281D01*
G01X161210Y-248531D02*
X161843Y-247697D01*
X162160Y-246864D01*
Y-243531D01*
X161843Y-242697D01*
X161210Y-241864D01*
G01X164600Y-245864D02*
X164980Y-246447D01*
X165486Y-246781D01*
X166056Y-246864D01*
X166563Y-246781D01*
X167070Y-246364D01*
X167386Y-245864D01*
X167450Y-245364D01*
X167323Y-244781D01*
X166880Y-244364D01*
X166436Y-244197D01*
X165866D01*
G01X166436D02*
X166816Y-243947D01*
X167133Y-243531D01*
X167260Y-243031D01*
X167133Y-242531D01*
X166816Y-242114D01*
X166246Y-241864D01*
X165676Y-241947D01*
X165106Y-242281D01*
G01X170016Y-246281D02*
X170460Y-246697D01*
X170966Y-246864D01*
X171473Y-246697D01*
X171916Y-246197D01*
X172233Y-245447D01*
X172360Y-244697D01*
Y-243781D01*
X172233Y-243031D01*
X171916Y-242364D01*
X171536Y-242031D01*
X171093Y-241864D01*
X170586Y-242031D01*
X170206Y-242364D01*
X169953Y-242864D01*
X169826Y-243531D01*
X169953Y-244114D01*
X170270Y-244697D01*
X170650Y-245031D01*
X171093Y-245114D01*
X171600Y-244947D01*
X171980Y-244531D01*
X172360Y-243781D01*
G01X176066Y-246864D02*
X176193Y-245781D01*
X176383Y-244864D01*
X176636Y-244031D01*
X176953Y-243114D01*
X177460Y-241864D01*
X174926D01*
G01X180470Y-245197D02*
X182116D01*
G01X185000Y-245864D02*
X185380Y-246447D01*
X185886Y-246781D01*
X186456Y-246864D01*
X186963Y-246781D01*
X187470Y-246364D01*
X187786Y-245864D01*
X187850Y-245364D01*
X187723Y-244781D01*
X187280Y-244364D01*
X186836Y-244197D01*
X186266D01*
G01X186836D02*
X187216Y-243947D01*
X187533Y-243531D01*
X187660Y-243031D01*
X187533Y-242531D01*
X187216Y-242114D01*
X186646Y-241864D01*
X186076Y-241947D01*
X185506Y-242281D01*
G01X190290Y-244781D02*
X190733Y-244197D01*
X191113Y-243864D01*
X191620Y-243697D01*
X192063Y-243864D01*
X192380Y-244197D01*
X192633Y-244697D01*
X192696Y-245281D01*
X192633Y-245781D01*
X192380Y-246281D01*
X192000Y-246697D01*
X191556Y-246864D01*
X191050Y-246697D01*
X190606Y-246197D01*
X190353Y-245447D01*
X190290Y-244614D01*
X190416Y-243531D01*
X190606Y-242947D01*
X190923Y-242364D01*
X191366Y-241947D01*
X191810Y-241864D01*
X192253Y-242031D01*
X192570Y-242447D01*
G01X196593Y-246864D02*
Y-241864D01*
X195833Y-242864D01*
G01Y-246864D02*
X197353D01*
G01X202453D02*
Y-241864D01*
X200110Y-245447D01*
X203276D01*
G01X26493Y-176864D02*
Y-251864D01*
X526493D01*
Y-176864D01*
X26493D01*
G01X221493D02*
Y-251864D01*
G01Y-226864D02*
X324493D01*
Y-201864D01*
G01X221493D02*
X324493D01*
G01X332000Y-236864D02*
Y-231864D01*
X333266D01*
X333773Y-232114D01*
X334153Y-232447D01*
X334470Y-232947D01*
X334723Y-233531D01*
X334786Y-234364D01*
X334723Y-235197D01*
X334470Y-235781D01*
X334153Y-236281D01*
X333773Y-236614D01*
X333266Y-236864D01*
X332000D01*
G01X336910D02*
X338493Y-231864D01*
X340076Y-236864D01*
G01X339506Y-235114D02*
X337480D01*
G01X343593Y-231864D02*
Y-236864D01*
G01X342136Y-231864D02*
X345050D01*
G01X349960Y-236864D02*
X347426D01*
Y-231864D01*
X349960D01*
G01X348946Y-234281D02*
X347426D01*
G01X353793Y-237031D02*
X353666Y-236947D01*
Y-236781D01*
X353793Y-236697D01*
X353920Y-236781D01*
Y-236947D01*
X353793Y-237031D01*
G01Y-234781D02*
X353666Y-234697D01*
Y-234531D01*
X353793Y-234447D01*
X353920Y-234531D01*
Y-234697D01*
X353793Y-234781D01*
G01X326493Y-176864D02*
Y-251864D01*
G01X324493Y-176864D02*
Y-251864D01*
G01X326493Y-226864D02*
X526493D01*
G01X332126Y-211864D02*
Y-206864D01*
X333646D01*
X334153Y-207114D01*
X334533Y-207697D01*
X334660Y-208364D01*
X334533Y-209031D01*
X334216Y-209531D01*
X333646Y-209781D01*
X332126D01*
G01X337353Y-212031D02*
X339633Y-206864D01*
G01X342136Y-211864D02*
Y-206864D01*
X345050Y-211864D01*
Y-206864D01*
G01X348693Y-212031D02*
X348566Y-211947D01*
Y-211781D01*
X348693Y-211697D01*
X348820Y-211781D01*
Y-211947D01*
X348693Y-212031D01*
G01Y-209781D02*
X348566Y-209697D01*
Y-209531D01*
X348693Y-209447D01*
X348820Y-209531D01*
Y-209697D01*
X348693Y-209781D01*
G01X326493Y-201864D02*
X526493D01*
G01X332126Y-186864D02*
Y-181864D01*
X333646D01*
X334153Y-182114D01*
X334533Y-182697D01*
X334660Y-183364D01*
X334533Y-184031D01*
X334216Y-184531D01*
X333646Y-184781D01*
X332126D01*
G01X337226Y-186864D02*
Y-181864D01*
X338810D01*
X339316Y-182114D01*
X339633Y-182447D01*
X339760Y-183114D01*
X339633Y-183781D01*
X339253Y-184197D01*
X338810Y-184447D01*
X337226D01*
G01X338810D02*
X339760Y-186864D01*
G01X343593D02*
X343086Y-186781D01*
X342643Y-186447D01*
X342263Y-185947D01*
X342010Y-185364D01*
X341883Y-184697D01*
Y-184031D01*
X342010Y-183364D01*
X342263Y-182781D01*
X342643Y-182281D01*
X343086Y-181947D01*
X343593Y-181864D01*
X344100Y-181947D01*
X344543Y-182281D01*
X344923Y-182781D01*
X345176Y-183364D01*
X345303Y-184031D01*
Y-184697D01*
X345176Y-185364D01*
X344923Y-185947D01*
X344543Y-186447D01*
X344100Y-186781D01*
X343593Y-186864D01*
G01X347426Y-185864D02*
X347743Y-186364D01*
X348123Y-186697D01*
X348566Y-186864D01*
X349073Y-186697D01*
X349453Y-186364D01*
X349833Y-185864D01*
X349960Y-185197D01*
Y-181864D01*
G01X355060Y-186864D02*
X352526D01*
Y-181864D01*
X355060D01*
G01X354046Y-184281D02*
X352526D01*
G01X360286Y-182281D02*
X359906Y-182031D01*
X359463Y-181864D01*
X358956D01*
X358386Y-182114D01*
X357943Y-182531D01*
X357626Y-183031D01*
X357373Y-183864D01*
X357310Y-184614D01*
X357436Y-185364D01*
X357626Y-185864D01*
X358006Y-186364D01*
X358450Y-186697D01*
X358893Y-186864D01*
X359336D01*
X359780Y-186697D01*
X360160Y-186447D01*
X360476Y-186114D01*
G01X363993Y-181864D02*
Y-186864D01*
G01X362536Y-181864D02*
X365450D01*
G01X369093Y-187031D02*
X368966Y-186947D01*
Y-186781D01*
X369093Y-186697D01*
X369220Y-186781D01*
Y-186947D01*
X369093Y-187031D01*
G01Y-184781D02*
X368966Y-184697D01*
Y-184531D01*
X369093Y-184447D01*
X369220Y-184531D01*
Y-184697D01*
X369093Y-184781D01*
G01X447126Y-236864D02*
Y-231864D01*
X448710D01*
X449216Y-232114D01*
X449533Y-232447D01*
X449660Y-233114D01*
X449533Y-233781D01*
X449153Y-234197D01*
X448710Y-234447D01*
X447126D01*
G01X448710D02*
X449660Y-236864D01*
G01X454760D02*
X452226D01*
Y-231864D01*
X454760D01*
G01X453746Y-234281D02*
X452226D01*
G01X457010Y-231864D02*
X458593Y-236864D01*
X460176Y-231864D01*
G01X463693Y-237031D02*
X463566Y-236947D01*
Y-236781D01*
X463693Y-236697D01*
X463820Y-236781D01*
Y-236947D01*
X463693Y-237031D01*
G01Y-234781D02*
X463566Y-234697D01*
Y-234531D01*
X463693Y-234447D01*
X463820Y-234531D01*
Y-234697D01*
X463693Y-234781D01*
G01X441493Y-226864D02*
Y-251864D01*
G01X490493Y-226864D02*
Y-251864D01*
G01X-1043962Y-705877D02*
Y2342823D01*
X2300638D01*
Y-705877D01*
X-1043962D01*
G01X37198Y-238524D02*
X37825Y-239049D01*
X38530Y-239364D01*
X39156D01*
X39783Y-239049D01*
X40253Y-238524D01*
X40488Y-237789D01*
X40331Y-237054D01*
X39940Y-236424D01*
X39235Y-236004D01*
X38295Y-235794D01*
X37746Y-235374D01*
X37511Y-234639D01*
X37668Y-233904D01*
X38060Y-233379D01*
X38608Y-233064D01*
X39156D01*
X39705Y-233274D01*
X40175Y-233799D01*
G01X43498Y-239364D02*
Y-233064D01*
G01X46788D02*
Y-239364D01*
G01Y-236214D02*
X43498D01*
G01X50503Y-233064D02*
X52383D01*
G01X51443D02*
Y-239364D01*
G01X50503D02*
X52383D01*
G01X59310D02*
X56176D01*
Y-233064D01*
X59310D01*
G01X58056Y-236109D02*
X56176D01*
G01X62241Y-239364D02*
Y-233064D01*
X65845Y-239364D01*
Y-233064D01*
G01X70186Y-240519D02*
X70500Y-239154D01*
G01X76643Y-233064D02*
Y-239364D01*
G01X74841Y-233064D02*
X78445D01*
G01X80985Y-239364D02*
X82943Y-233064D01*
X84901Y-239364D01*
G01X84196Y-237159D02*
X81690D01*
G01X88303Y-233064D02*
X90183D01*
G01X89243D02*
Y-239364D01*
G01X88303D02*
X90183D01*
G01X93193Y-233064D02*
X94290Y-239364D01*
X95543Y-233064D01*
X96796Y-239364D01*
X97893Y-233064D01*
G01X99885Y-239364D02*
X101843Y-233064D01*
X103801Y-239364D01*
G01X103096Y-237159D02*
X100590D01*
G01X106341Y-239364D02*
Y-233064D01*
X109945Y-239364D01*
Y-233064D01*
G01X119176Y-239364D02*
Y-233064D01*
X121135D01*
X121761Y-233379D01*
X122153Y-233799D01*
X122310Y-234639D01*
X122153Y-235479D01*
X121683Y-236004D01*
X121135Y-236319D01*
X119176D01*
G01X121135D02*
X122310Y-239364D01*
G01X127043Y-239574D02*
X126886Y-239469D01*
Y-239259D01*
X127043Y-239154D01*
X127200Y-239259D01*
Y-239469D01*
X127043Y-239574D01*
G01X133343Y-239364D02*
X132716Y-239259D01*
X132168Y-238839D01*
X131698Y-238209D01*
X131385Y-237474D01*
X131228Y-236634D01*
Y-235794D01*
X131385Y-234954D01*
X131698Y-234219D01*
X132168Y-233589D01*
X132716Y-233169D01*
X133343Y-233064D01*
X133970Y-233169D01*
X134518Y-233589D01*
X134988Y-234219D01*
X135301Y-234954D01*
X135458Y-235794D01*
Y-236634D01*
X135301Y-237474D01*
X134988Y-238209D01*
X134518Y-238839D01*
X133970Y-239259D01*
X133343Y-239364D01*
G01X139643Y-239574D02*
X139486Y-239469D01*
Y-239259D01*
X139643Y-239154D01*
X139800Y-239259D01*
Y-239469D01*
X139643Y-239574D01*
G01X147666Y-233589D02*
X147196Y-233274D01*
X146648Y-233064D01*
X146021D01*
X145316Y-233379D01*
X144768Y-233904D01*
X144376Y-234534D01*
X144063Y-235584D01*
X143985Y-236529D01*
X144141Y-237474D01*
X144376Y-238104D01*
X144846Y-238734D01*
X145395Y-239154D01*
X145943Y-239364D01*
X146491D01*
X147040Y-239154D01*
X147510Y-238839D01*
X147901Y-238419D01*
G01X152243Y-239574D02*
X152086Y-239469D01*
Y-239259D01*
X152243Y-239154D01*
X152400Y-239259D01*
Y-239469D01*
X152243Y-239574D01*
G01X37120Y-229364D02*
Y-223064D01*
G01X40096D02*
X37120Y-226949D01*
G01X40566Y-229364D02*
X38451Y-225164D01*
G01X43420Y-223064D02*
Y-227579D01*
X43733Y-228524D01*
X44360Y-229154D01*
X45143Y-229364D01*
X45926Y-229154D01*
X46553Y-228524D01*
X46866Y-227579D01*
Y-223064D01*
G01X53010Y-229364D02*
X49876D01*
Y-223064D01*
X53010D01*
G01X51756Y-226109D02*
X49876D01*
G01X56803Y-223064D02*
X58683D01*
G01X57743D02*
Y-229364D01*
G01X56803D02*
X58683D01*
G01X68698Y-228524D02*
X69325Y-229049D01*
X70030Y-229364D01*
X70656D01*
X71283Y-229049D01*
X71753Y-228524D01*
X71988Y-227789D01*
X71831Y-227054D01*
X71440Y-226424D01*
X70735Y-226004D01*
X69795Y-225794D01*
X69246Y-225374D01*
X69011Y-224639D01*
X69168Y-223904D01*
X69560Y-223379D01*
X70108Y-223064D01*
X70656D01*
X71205Y-223274D01*
X71675Y-223799D01*
G01X74998Y-229364D02*
Y-223064D01*
G01X78288D02*
Y-229364D01*
G01Y-226214D02*
X74998D01*
G01X80985Y-229364D02*
X82943Y-223064D01*
X84901Y-229364D01*
G01X84196Y-227159D02*
X81690D01*
G01X87441Y-229364D02*
Y-223064D01*
X91045Y-229364D01*
Y-223064D01*
G01X100198Y-229364D02*
Y-223064D01*
G01X103488D02*
Y-229364D01*
G01Y-226214D02*
X100198D01*
G01X106498Y-228524D02*
X107125Y-229049D01*
X107830Y-229364D01*
X108456D01*
X109083Y-229049D01*
X109553Y-228524D01*
X109788Y-227789D01*
X109631Y-227054D01*
X109240Y-226424D01*
X108535Y-226004D01*
X107595Y-225794D01*
X107046Y-225374D01*
X106811Y-224639D01*
X106968Y-223904D01*
X107360Y-223379D01*
X107908Y-223064D01*
X108456D01*
X109005Y-223274D01*
X109475Y-223799D01*
G01X113503Y-223064D02*
X115383D01*
G01X114443D02*
Y-229364D01*
G01X113503D02*
X115383D01*
G01X118785D02*
X120743Y-223064D01*
X122701Y-229364D01*
G01X121996Y-227159D02*
X119490D01*
G01X125241Y-229364D02*
Y-223064D01*
X128845Y-229364D01*
Y-223064D01*
G01X133813Y-226214D02*
X135380D01*
Y-228104D01*
X134910Y-228734D01*
X134361Y-229154D01*
X133578Y-229364D01*
X132795Y-229154D01*
X132246Y-228734D01*
X131776Y-228104D01*
X131463Y-227369D01*
X131306Y-226529D01*
Y-225794D01*
X131463Y-225164D01*
X131776Y-224429D01*
X132246Y-223799D01*
X132716Y-223379D01*
X133343Y-223064D01*
X133891D01*
X134518Y-223274D01*
X134988Y-223694D01*
G01X139486Y-230519D02*
X139800Y-229154D01*
G01X145943Y-223064D02*
Y-229364D01*
G01X144141Y-223064D02*
X147745D01*
G01X150285Y-229364D02*
X152243Y-223064D01*
X154201Y-229364D01*
G01X153496Y-227159D02*
X150990D01*
G01X158543Y-229364D02*
X157916Y-229259D01*
X157368Y-228839D01*
X156898Y-228209D01*
X156585Y-227474D01*
X156428Y-226634D01*
Y-225794D01*
X156585Y-224954D01*
X156898Y-224219D01*
X157368Y-223589D01*
X157916Y-223169D01*
X158543Y-223064D01*
X159170Y-223169D01*
X159718Y-223589D01*
X160188Y-224219D01*
X160501Y-224954D01*
X160658Y-225794D01*
Y-226634D01*
X160501Y-227474D01*
X160188Y-228209D01*
X159718Y-228839D01*
X159170Y-229259D01*
X158543Y-229364D01*
G01X171143D02*
Y-226529D01*
X169576Y-223064D01*
G01X172710D02*
X171143Y-226529D01*
G01X175720Y-223064D02*
Y-227579D01*
X176033Y-228524D01*
X176660Y-229154D01*
X177443Y-229364D01*
X178226Y-229154D01*
X178853Y-228524D01*
X179166Y-227579D01*
Y-223064D01*
G01X181785Y-229364D02*
X183743Y-223064D01*
X185701Y-229364D01*
G01X184996Y-227159D02*
X182490D01*
G01X188241Y-229364D02*
Y-223064D01*
X191845Y-229364D01*
Y-223064D01*
G01X37041Y-219364D02*
Y-213064D01*
X40645Y-219364D01*
Y-213064D01*
G01X45143Y-219364D02*
X44516Y-219259D01*
X43968Y-218839D01*
X43498Y-218209D01*
X43185Y-217474D01*
X43028Y-216634D01*
Y-215794D01*
X43185Y-214954D01*
X43498Y-214219D01*
X43968Y-213589D01*
X44516Y-213169D01*
X45143Y-213064D01*
X45770Y-213169D01*
X46318Y-213589D01*
X46788Y-214219D01*
X47101Y-214954D01*
X47258Y-215794D01*
Y-216634D01*
X47101Y-217474D01*
X46788Y-218209D01*
X46318Y-218839D01*
X45770Y-219259D01*
X45143Y-219364D01*
G01X51443Y-219574D02*
X51286Y-219469D01*
Y-219259D01*
X51443Y-219154D01*
X51600Y-219259D01*
Y-219469D01*
X51443Y-219574D01*
G01X57743Y-219364D02*
Y-213064D01*
X56803Y-214324D01*
G01Y-219364D02*
X58683D01*
G01X64043D02*
X64591Y-219259D01*
X65218Y-218944D01*
X65610Y-218419D01*
X65766Y-217684D01*
X65610Y-216949D01*
X65140Y-216319D01*
X64435Y-216004D01*
X63651D01*
X63181Y-215794D01*
X62790Y-215269D01*
X62633Y-214534D01*
X62868Y-213799D01*
X63416Y-213274D01*
X64043Y-213064D01*
X64670Y-213274D01*
X65218Y-213799D01*
X65453Y-214534D01*
X65296Y-215269D01*
X64905Y-215794D01*
X64435Y-216004D01*
X63651D01*
X62946Y-216319D01*
X62476Y-216949D01*
X62320Y-217684D01*
X62476Y-218419D01*
X62868Y-218944D01*
X63495Y-219259D01*
X64043Y-219364D01*
G01X70343D02*
X70891Y-219259D01*
X71518Y-218944D01*
X71910Y-218419D01*
X72066Y-217684D01*
X71910Y-216949D01*
X71440Y-216319D01*
X70735Y-216004D01*
X69951D01*
X69481Y-215794D01*
X69090Y-215269D01*
X68933Y-214534D01*
X69168Y-213799D01*
X69716Y-213274D01*
X70343Y-213064D01*
X70970Y-213274D01*
X71518Y-213799D01*
X71753Y-214534D01*
X71596Y-215269D01*
X71205Y-215794D01*
X70735Y-216004D01*
X69951D01*
X69246Y-216319D01*
X68776Y-216949D01*
X68620Y-217684D01*
X68776Y-218419D01*
X69168Y-218944D01*
X69795Y-219259D01*
X70343Y-219364D01*
G01X76486Y-220519D02*
X76800Y-219154D01*
G01X80593Y-213064D02*
X81690Y-219364D01*
X82943Y-213064D01*
X84196Y-219364D01*
X85293Y-213064D01*
G01X90810Y-219364D02*
X87676D01*
Y-213064D01*
X90810D01*
G01X89556Y-216109D02*
X87676D01*
G01X93741Y-219364D02*
Y-213064D01*
X97345Y-219364D01*
Y-213064D01*
G01X106498Y-219364D02*
Y-213064D01*
G01X109788D02*
Y-219364D01*
G01Y-216214D02*
X106498D01*
G01X112093Y-213064D02*
X113190Y-219364D01*
X114443Y-213064D01*
X115696Y-219364D01*
X116793Y-213064D01*
G01X118785Y-219364D02*
X120743Y-213064D01*
X122701Y-219364D01*
G01X121996Y-217159D02*
X119490D01*
G01X131855Y-214114D02*
X132325Y-213484D01*
X132873Y-213169D01*
X133500Y-213064D01*
X134283Y-213274D01*
X134831Y-213799D01*
X134988Y-214429D01*
X134910Y-215059D01*
X134596Y-215584D01*
X133030Y-216634D01*
X132325Y-217369D01*
X131855Y-218419D01*
X131698Y-219364D01*
X134988D01*
G01X137841D02*
Y-213064D01*
X141445Y-219364D01*
Y-213064D01*
G01X144220Y-219364D02*
Y-213064D01*
X145786D01*
X146413Y-213379D01*
X146883Y-213799D01*
X147275Y-214429D01*
X147588Y-215164D01*
X147666Y-216214D01*
X147588Y-217264D01*
X147275Y-217999D01*
X146883Y-218629D01*
X146413Y-219049D01*
X145786Y-219364D01*
X144220D01*
G01X156976D02*
Y-213064D01*
X158935D01*
X159561Y-213379D01*
X159953Y-213799D01*
X160110Y-214639D01*
X159953Y-215479D01*
X159483Y-216004D01*
X158935Y-216319D01*
X156976D01*
G01X158935D02*
X160110Y-219364D01*
G01X163120D02*
Y-213064D01*
X164686D01*
X165313Y-213379D01*
X165783Y-213799D01*
X166175Y-214429D01*
X166488Y-215164D01*
X166566Y-216214D01*
X166488Y-217264D01*
X166175Y-217999D01*
X165783Y-218629D01*
X165313Y-219049D01*
X164686Y-219364D01*
X163120D01*
G01X171143Y-219574D02*
X170986Y-219469D01*
Y-219259D01*
X171143Y-219154D01*
X171300Y-219259D01*
Y-219469D01*
X171143Y-219574D01*
G01X61143Y-206664D02*
X58623Y-206247D01*
X56418Y-204581D01*
X54528Y-202081D01*
X53268Y-199164D01*
X52638Y-195831D01*
Y-192497D01*
X53268Y-189164D01*
X54528Y-186247D01*
X56418Y-183748D01*
X58623Y-182081D01*
X61143Y-181664D01*
X63663Y-182081D01*
X65868Y-183748D01*
X67758Y-186247D01*
X69018Y-189164D01*
X69648Y-192497D01*
Y-195831D01*
X69018Y-199164D01*
X67758Y-202081D01*
X65868Y-204581D01*
X63663Y-206247D01*
X61143Y-206664D01*
G01X63663Y-199997D02*
X67443Y-206664D01*
G01X80988Y-189998D02*
Y-201664D01*
X82248Y-204581D01*
X84138Y-206247D01*
X86343Y-206664D01*
X88548Y-206247D01*
X90438Y-204581D01*
X91698Y-201664D01*
G01Y-206664D02*
Y-189998D01*
G01X117213Y-206664D02*
Y-189998D01*
G01Y-192914D02*
X115953Y-191248D01*
X114063Y-190414D01*
X111858Y-189998D01*
X109653Y-190831D01*
X107763Y-192497D01*
X106503Y-194998D01*
X105873Y-198331D01*
X106503Y-201664D01*
X107763Y-204165D01*
X109653Y-205831D01*
X111858Y-206664D01*
X114063Y-206247D01*
X115953Y-204998D01*
X117213Y-203331D01*
G01X131388Y-206664D02*
Y-189998D01*
G01Y-194164D02*
X132648Y-192081D01*
X134538Y-190414D01*
X137058Y-189998D01*
X139263Y-190414D01*
X141153Y-192081D01*
X142098Y-194998D01*
Y-206664D01*
G01X161943Y-181664D02*
Y-206664D01*
G01X157533Y-189998D02*
X166353D01*
G01X192813Y-206664D02*
Y-189998D01*
G01Y-192914D02*
X191553Y-191248D01*
X189663Y-190414D01*
X187458Y-189998D01*
X185253Y-190831D01*
X183363Y-192497D01*
X182103Y-194998D01*
X181473Y-198331D01*
X182103Y-201664D01*
X183363Y-204165D01*
X185253Y-205831D01*
X187458Y-206664D01*
X189663Y-206247D01*
X191553Y-204998D01*
X192813Y-203331D01*
G01X232493Y-186364D02*
Y-194364D01*
X236493D01*
G01X244293D02*
Y-189031D01*
G01Y-189964D02*
X243893Y-189431D01*
X243293Y-189164D01*
X242593Y-189031D01*
X241893Y-189297D01*
X241293Y-189831D01*
X240893Y-190631D01*
X240693Y-191697D01*
X240893Y-192764D01*
X241293Y-193564D01*
X241893Y-194097D01*
X242593Y-194364D01*
X243293Y-194231D01*
X243893Y-193831D01*
X244293Y-193298D01*
G01X248393Y-196764D02*
X248993Y-197031D01*
X249793Y-196764D01*
X250293Y-196231D01*
X250693Y-195564D01*
X251293Y-193431D01*
X252593Y-189031D01*
G01X249393D02*
X251293Y-193431D01*
G01X256993Y-190764D02*
X260193D01*
X259893Y-189831D01*
X259393Y-189297D01*
X258693Y-189031D01*
X257993Y-189164D01*
X257393Y-189564D01*
X256993Y-190497D01*
X256793Y-191298D01*
Y-192097D01*
X256993Y-192897D01*
X257493Y-193697D01*
X258093Y-194231D01*
X258793Y-194364D01*
X259493Y-194097D01*
X260193Y-193298D01*
G01X265093Y-194364D02*
Y-189031D01*
G01Y-190097D02*
X265593Y-189564D01*
X266093Y-189164D01*
X266793Y-189031D01*
X267293Y-189164D01*
X267893Y-189564D01*
G01X254793Y-236364D02*
X257193D01*
G01X255993D02*
Y-244364D01*
G01X254793D02*
X257193D01*
G01X262593D02*
Y-239031D01*
G01Y-240097D02*
X263093Y-239564D01*
X263593Y-239164D01*
X264293Y-239031D01*
X264793Y-239164D01*
X265393Y-239564D01*
G01X270493Y-240764D02*
X273693D01*
X273393Y-239831D01*
X272893Y-239297D01*
X272193Y-239031D01*
X271493Y-239164D01*
X270893Y-239564D01*
X270493Y-240497D01*
X270293Y-241298D01*
Y-242097D01*
X270493Y-242897D01*
X270993Y-243697D01*
X271593Y-244231D01*
X272293Y-244364D01*
X272993Y-244097D01*
X273693Y-243298D01*
G01X278293Y-244364D02*
Y-239031D01*
G01Y-240364D02*
X278693Y-239697D01*
X279293Y-239164D01*
X280093Y-239031D01*
X280793Y-239164D01*
X281393Y-239697D01*
X281693Y-240631D01*
Y-244364D01*
G01X286493Y-240764D02*
X289693D01*
X289393Y-239831D01*
X288893Y-239297D01*
X288193Y-239031D01*
X287493Y-239164D01*
X286893Y-239564D01*
X286493Y-240497D01*
X286293Y-241298D01*
Y-242097D01*
X286493Y-242897D01*
X286993Y-243697D01*
X287593Y-244231D01*
X288293Y-244364D01*
X288993Y-244097D01*
X289693Y-243298D01*
G01X262293Y-211364D02*
X264693D01*
G01X263493D02*
Y-219364D01*
G01X262293D02*
X264693D01*
G01X269193D02*
Y-211364D01*
X273793Y-219364D01*
Y-211364D01*
G01X279493Y-219364D02*
Y-211364D01*
X278293Y-212964D01*
G01Y-219364D02*
X280693D01*
G01X283793Y-192764D02*
X284393Y-193697D01*
X285193Y-194231D01*
X286093Y-194364D01*
X286893Y-194231D01*
X287693Y-193564D01*
X288193Y-192764D01*
X288293Y-191964D01*
X288093Y-191031D01*
X287393Y-190364D01*
X286693Y-190097D01*
X285793D01*
G01X286693D02*
X287293Y-189697D01*
X287793Y-189031D01*
X287993Y-188231D01*
X287793Y-187431D01*
X287293Y-186764D01*
X286393Y-186364D01*
X285493Y-186497D01*
X284593Y-187031D01*
G01X359093Y-237697D02*
X359693Y-236897D01*
X360393Y-236497D01*
X361193Y-236364D01*
X362193Y-236631D01*
X362893Y-237297D01*
X363093Y-238097D01*
X362993Y-238898D01*
X362593Y-239564D01*
X360593Y-240897D01*
X359693Y-241831D01*
X359093Y-243164D01*
X358893Y-244364D01*
X363093D01*
G01X368993Y-236364D02*
X368193Y-236631D01*
X367593Y-237297D01*
X367193Y-238097D01*
X366893Y-239164D01*
X366793Y-240364D01*
X366893Y-241564D01*
X367193Y-242631D01*
X367593Y-243431D01*
X368193Y-244097D01*
X368993Y-244364D01*
X369793Y-244097D01*
X370393Y-243431D01*
X370793Y-242631D01*
X371093Y-241564D01*
X371193Y-240364D01*
X371093Y-239164D01*
X370793Y-238097D01*
X370393Y-237297D01*
X369793Y-236631D01*
X368993Y-236364D01*
G01X376993Y-244364D02*
Y-236364D01*
X375793Y-237964D01*
G01Y-244364D02*
X378193D01*
G01X383093Y-237697D02*
X383693Y-236897D01*
X384393Y-236497D01*
X385193Y-236364D01*
X386193Y-236631D01*
X386893Y-237297D01*
X387093Y-238097D01*
X386993Y-238898D01*
X386593Y-239564D01*
X384593Y-240897D01*
X383693Y-241831D01*
X383093Y-243164D01*
X382893Y-244364D01*
X387093D01*
G01X391193Y-244631D02*
X394793Y-236364D01*
G01X400993Y-244364D02*
Y-236364D01*
X399793Y-237964D01*
G01Y-244364D02*
X402193D01*
G01X408993Y-236364D02*
X408193Y-236631D01*
X407593Y-237297D01*
X407193Y-238097D01*
X406893Y-239164D01*
X406793Y-240364D01*
X406893Y-241564D01*
X407193Y-242631D01*
X407593Y-243431D01*
X408193Y-244097D01*
X408993Y-244364D01*
X409793Y-244097D01*
X410393Y-243431D01*
X410793Y-242631D01*
X411093Y-241564D01*
X411193Y-240364D01*
X411093Y-239164D01*
X410793Y-238097D01*
X410393Y-237297D01*
X409793Y-236631D01*
X408993Y-236364D01*
G01X415193Y-244631D02*
X418793Y-236364D01*
G01X422793Y-242764D02*
X423393Y-243697D01*
X424193Y-244231D01*
X425093Y-244364D01*
X425893Y-244231D01*
X426693Y-243564D01*
X427193Y-242764D01*
X427293Y-241964D01*
X427093Y-241031D01*
X426393Y-240364D01*
X425693Y-240097D01*
X424793D01*
G01X425693D02*
X426293Y-239697D01*
X426793Y-239031D01*
X426993Y-238231D01*
X426793Y-237431D01*
X426293Y-236764D01*
X425393Y-236364D01*
X424493Y-236497D01*
X423593Y-237031D01*
G01X432993Y-244364D02*
Y-236364D01*
X431793Y-237964D01*
G01Y-244364D02*
X434193D01*
G01X358793Y-219364D02*
Y-211364D01*
X360793D01*
X361593Y-211764D01*
X362193Y-212297D01*
X362693Y-213097D01*
X363093Y-214031D01*
X363193Y-215364D01*
X363093Y-216697D01*
X362693Y-217631D01*
X362193Y-218431D01*
X361593Y-218964D01*
X360793Y-219364D01*
X358793D01*
G01X366493D02*
X368993Y-211364D01*
X371493Y-219364D01*
G01X370593Y-216564D02*
X367393D01*
G01X376993Y-211364D02*
Y-219364D01*
G01X374693Y-211364D02*
X379293D01*
G01X383093Y-216031D02*
X383793Y-215097D01*
X384393Y-214564D01*
X385193Y-214297D01*
X385893Y-214564D01*
X386393Y-215097D01*
X386793Y-215897D01*
X386893Y-216831D01*
X386793Y-217631D01*
X386393Y-218431D01*
X385793Y-219097D01*
X385093Y-219364D01*
X384293Y-219097D01*
X383593Y-218298D01*
X383193Y-217097D01*
X383093Y-215764D01*
X383293Y-214031D01*
X383593Y-213097D01*
X384093Y-212164D01*
X384793Y-211497D01*
X385493Y-211364D01*
X386193Y-211631D01*
X386693Y-212297D01*
G01X390393Y-219364D02*
Y-211364D01*
X392993Y-218031D01*
X395593Y-211364D01*
Y-219364D01*
G01X400993Y-211364D02*
Y-219364D01*
G01X398693Y-211364D02*
X403293D01*
G01X406893Y-219364D02*
Y-211364D01*
G01X411093D02*
Y-219364D01*
G01Y-215364D02*
X406893D01*
G01X414793Y-217764D02*
X415393Y-218697D01*
X416193Y-219231D01*
X417093Y-219364D01*
X417893Y-219231D01*
X418693Y-218564D01*
X419193Y-217764D01*
X419293Y-216964D01*
X419093Y-216031D01*
X418393Y-215364D01*
X417693Y-215097D01*
X416793D01*
G01X417693D02*
X418293Y-214697D01*
X418793Y-214031D01*
X418993Y-213231D01*
X418793Y-212431D01*
X418293Y-211764D01*
X417393Y-211364D01*
X416493Y-211497D01*
X415593Y-212031D01*
G01X422493Y-219364D02*
X424993Y-211364D01*
X427493Y-219364D01*
G01X426593Y-216564D02*
X423393D01*
G01X430793Y-219364D02*
Y-211364D01*
X432793D01*
X433593Y-211764D01*
X434193Y-212297D01*
X434693Y-213097D01*
X435093Y-214031D01*
X435193Y-215364D01*
X435093Y-216697D01*
X434693Y-217631D01*
X434193Y-218431D01*
X433593Y-218964D01*
X432793Y-219364D01*
X430793D01*
G01X440993Y-211364D02*
X440193Y-211631D01*
X439593Y-212297D01*
X439193Y-213097D01*
X438893Y-214164D01*
X438793Y-215364D01*
X438893Y-216564D01*
X439193Y-217631D01*
X439593Y-218431D01*
X440193Y-219097D01*
X440993Y-219364D01*
X441793Y-219097D01*
X442393Y-218431D01*
X442793Y-217631D01*
X443093Y-216564D01*
X443193Y-215364D01*
X443093Y-214164D01*
X442793Y-213097D01*
X442393Y-212297D01*
X441793Y-211631D01*
X440993Y-211364D01*
G01X380993Y-186364D02*
Y-194364D01*
G01X378693Y-186364D02*
X383293D01*
G01X387093Y-191031D02*
X387793Y-190097D01*
X388393Y-189564D01*
X389193Y-189297D01*
X389893Y-189564D01*
X390393Y-190097D01*
X390793Y-190897D01*
X390893Y-191831D01*
X390793Y-192631D01*
X390393Y-193431D01*
X389793Y-194097D01*
X389093Y-194364D01*
X388293Y-194097D01*
X387593Y-193298D01*
X387193Y-192097D01*
X387093Y-190764D01*
X387293Y-189031D01*
X387593Y-188097D01*
X388093Y-187164D01*
X388793Y-186497D01*
X389493Y-186364D01*
X390193Y-186631D01*
X390693Y-187297D01*
G01X394393Y-194364D02*
Y-186364D01*
X396993Y-193031D01*
X399593Y-186364D01*
Y-194364D01*
G01X401993Y-197031D02*
X407993D01*
G01X415193Y-187031D02*
X414593Y-186631D01*
X413893Y-186364D01*
X413093D01*
X412193Y-186764D01*
X411493Y-187431D01*
X410993Y-188231D01*
X410593Y-189564D01*
X410493Y-190764D01*
X410693Y-191964D01*
X410993Y-192764D01*
X411593Y-193564D01*
X412293Y-194097D01*
X412993Y-194364D01*
X413693D01*
X414393Y-194097D01*
X414993Y-193697D01*
X415493Y-193164D01*
G01X418393Y-194364D02*
Y-186364D01*
X420993Y-193031D01*
X423593Y-186364D01*
Y-194364D01*
G01X425993Y-197031D02*
X431993D01*
G01X434793Y-194364D02*
Y-186364D01*
X436793D01*
X437593Y-186764D01*
X438193Y-187297D01*
X438693Y-188097D01*
X439093Y-189031D01*
X439193Y-190364D01*
X439093Y-191697D01*
X438693Y-192631D01*
X438193Y-193431D01*
X437593Y-193964D01*
X436793Y-194364D01*
X434793D01*
G01X473793Y-244364D02*
Y-236364D01*
X475793D01*
X476593Y-236764D01*
X477193Y-237297D01*
X477693Y-238097D01*
X478093Y-239031D01*
X478193Y-240364D01*
X478093Y-241697D01*
X477693Y-242631D01*
X477193Y-243431D01*
X476593Y-243964D01*
X475793Y-244364D01*
X473793D01*
G01X503493D02*
Y-236364D01*
X502293Y-237964D01*
G01Y-244364D02*
X504693D01*
G01X509593Y-241031D02*
X510293Y-240097D01*
X510893Y-239564D01*
X511693Y-239297D01*
X512393Y-239564D01*
X512893Y-240097D01*
X513293Y-240897D01*
X513393Y-241831D01*
X513293Y-242631D01*
X512893Y-243431D01*
X512293Y-244097D01*
X511593Y-244364D01*
X510793Y-244097D01*
X510093Y-243298D01*
X509693Y-242097D01*
X509593Y-240764D01*
X509793Y-239031D01*
X510093Y-238097D01*
X510593Y-237164D01*
X511293Y-236497D01*
X511993Y-236364D01*
X512693Y-236631D01*
X513193Y-237297D01*
G54D14*
X556181Y81889D03*
G54D24*
G01X177763Y121057D02*
Y120824D01*
X175528Y118589D01*
X163687D01*
X162780Y119496D01*
Y121677D01*
X161785Y122672D01*
X157518D01*
X154540Y125650D01*
Y130401D01*
X132650Y152291D01*
Y157729D01*
X131830Y158549D01*
X130660D01*
X129840Y159369D01*
Y160529D01*
X130660Y161349D01*
X131830D01*
X132650Y162169D01*
Y163329D01*
X131830Y164149D01*
X130660D01*
X129840Y164969D01*
Y166129D01*
X130660Y166949D01*
X131830D01*
X132650Y167769D01*
Y168929D01*
X131830Y169749D01*
X130660D01*
X129840Y170569D01*
Y171729D01*
X130660Y172549D01*
X131830D01*
X132650Y173369D01*
Y174529D01*
X131830Y175349D01*
X130660D01*
X129840Y176169D01*
Y177329D01*
X130660Y178149D01*
X131830D01*
X132650Y178969D01*
Y180129D01*
X131830Y180949D01*
X130660D01*
X129840Y181769D01*
Y182929D01*
X130660Y183749D01*
X131830D01*
X132650Y184569D01*
Y185729D01*
X131830Y186549D01*
X130660D01*
X129840Y187369D01*
Y188529D01*
X130660Y189349D01*
X131830D01*
X132650Y190169D01*
Y191329D01*
X131830Y192149D01*
X130660D01*
X129840Y192969D01*
Y194129D01*
X130660Y194949D01*
X131830D01*
X132650Y195769D01*
Y196929D01*
X131830Y197749D01*
X130660D01*
X129840Y198569D01*
Y199729D01*
X130660Y200549D01*
X131830D01*
X132650Y201369D01*
Y202529D01*
X131830Y203349D01*
X130660D01*
X129840Y204169D01*
Y205329D01*
X130660Y206149D01*
X131830D01*
X132650Y206969D01*
Y208129D01*
X131830Y208949D01*
X130660D01*
X129840Y209769D01*
Y210929D01*
X130660Y211749D01*
X131830D01*
X132650Y212569D01*
Y214580D01*
X131830Y215400D01*
X130560D01*
X129740Y216220D01*
Y217380D01*
X130560Y218200D01*
X131830D01*
X133458Y219828D01*
Y220988D01*
X132433Y222013D01*
Y223173D01*
X133253Y223993D01*
X134413D01*
X135438Y222968D01*
X136598D01*
X137510Y223880D01*
Y225666D01*
X138963Y227119D01*
Y228279D01*
X137551Y229691D01*
Y230851D01*
X138371Y231671D01*
X139531D01*
X140943Y230259D01*
X142103D01*
X144368Y232524D01*
X157442D01*
X159134Y234216D01*
X175906D01*
X176726Y235036D01*
Y237196D01*
X177546Y238016D01*
X178706D01*
X179526Y237196D01*
Y237187D01*
X180716Y235997D01*
X182613D01*
X183550Y235060D01*
G01X184296Y241098D02*
X175542D01*
X172345Y237901D01*
X158225D01*
X155737Y235413D01*
X154205D01*
X153385Y236233D01*
Y237144D01*
X152565Y237964D01*
X151405D01*
X150585Y237144D01*
Y236233D01*
X149765Y235413D01*
X138214D01*
X134127Y231326D01*
Y230166D01*
X134993Y229300D01*
Y228140D01*
X134173Y227320D01*
X133013D01*
X132147Y228186D01*
X130987D01*
X127110Y224309D01*
Y154293D01*
X151550Y129853D01*
Y125031D01*
X160784Y115797D01*
X166511D01*
X167331Y114977D01*
Y111503D01*
X168151Y110683D01*
X169311D01*
X170131Y111503D01*
Y114977D01*
X170951Y115797D01*
X175851D01*
X177510Y114138D01*
Y108370D01*
X180150Y105730D01*
Y99913D01*
X179823Y99586D01*
Y94660D01*
X177733Y92570D01*
Y91967D01*
G01X177680Y101764D02*
X176790Y102654D01*
X168778D01*
X164200Y107232D01*
Y111043D01*
X162269Y112974D01*
X160051D01*
X148470Y124555D01*
Y129378D01*
X124610Y153238D01*
Y225502D01*
X137023Y237915D01*
X147454D01*
X150692Y241153D01*
X164435D01*
X165590Y242308D01*
Y243920D01*
X167344Y245674D01*
X169279D01*
X170544Y246939D01*
X172079D01*
X173344Y245674D01*
X174879D01*
X176144Y246939D01*
X177679D01*
X178944Y245674D01*
X187107D01*
X187927Y246494D01*
Y248877D01*
X188747Y249697D01*
X189907D01*
X190727Y248877D01*
Y246494D01*
X191547Y245674D01*
X197096D01*
X198685Y244085D01*
G01X175573Y226384D02*
X169623D01*
X165289Y222050D01*
X155813D01*
X145110Y211347D01*
Y207909D01*
X144290Y207089D01*
X143231D01*
X141650Y205508D01*
Y203270D01*
X143231Y201689D01*
X144290D01*
X145110Y200869D01*
Y199709D01*
X144290Y198889D01*
X143231D01*
X141650Y197308D01*
Y195070D01*
X143231Y193489D01*
X144290D01*
X145110Y192669D01*
Y191509D01*
X144290Y190689D01*
X143231D01*
X141650Y189108D01*
Y186870D01*
X143231Y185289D01*
X144290D01*
X145110Y184469D01*
Y183309D01*
X144290Y182489D01*
X143231D01*
X141650Y180908D01*
Y178670D01*
X143231Y177089D01*
X144290D01*
X145110Y176269D01*
Y175109D01*
X144290Y174289D01*
X143231D01*
X141650Y172708D01*
Y170470D01*
X143231Y168889D01*
X144290D01*
X145110Y168069D01*
Y166909D01*
X144290Y166089D01*
X143231D01*
X141650Y164508D01*
Y162270D01*
X143231Y160689D01*
X144290D01*
X145110Y159869D01*
Y153834D01*
X159276Y139668D01*
X180175D01*
X191520Y128323D01*
Y126455D01*
X189540Y124475D01*
Y115256D01*
X191143Y113653D01*
Y103881D01*
X193290Y101734D01*
Y98359D01*
X191665Y96734D01*
X188207D01*
X186723Y95250D01*
Y93642D01*
X184928Y91847D01*
G01X183013Y98813D02*
Y107564D01*
X183790Y108341D01*
Y110545D01*
X180820Y113515D01*
Y129181D01*
X176910Y133091D01*
X173508D01*
X171809Y131376D01*
X168121D01*
X166422Y133091D01*
X155794D01*
X135150Y153735D01*
Y216964D01*
X140640Y222454D01*
Y225254D01*
X145076Y229690D01*
X159674D01*
X161418Y231434D01*
X182755D01*
X184050Y230139D01*
G01X178040Y228978D02*
X166400D01*
X163556Y226134D01*
X154177D01*
X151828Y223785D01*
X150668D01*
X147271Y227181D01*
X146113D01*
X145291Y226359D01*
Y225201D01*
X148688Y221805D01*
Y220645D01*
X147868Y219825D01*
X146708D01*
X144712Y221821D01*
X143552D01*
X142732Y221001D01*
Y219841D01*
X144728Y217845D01*
Y216685D01*
X143908Y215865D01*
X142748D01*
X140752Y217861D01*
X139592D01*
X138772Y217041D01*
Y215881D01*
X140768Y213885D01*
Y212725D01*
X137650Y209607D01*
Y155637D01*
X157696Y135591D01*
X178498D01*
X185400Y128689D01*
Y126460D01*
X183740Y124800D01*
Y115114D01*
X186920Y111934D01*
Y107547D01*
X186026Y106653D01*
Y103484D01*
X189406Y100104D01*
X189700D01*
X190100Y99704D01*
Y99701D01*
G01X189928Y91847D02*
X188023Y93752D01*
Y94711D01*
X188746Y95434D01*
X192204D01*
X194590Y97820D01*
Y102273D01*
X192443Y104420D01*
Y114192D01*
X190840Y115795D01*
Y123936D01*
X192820Y125916D01*
Y128862D01*
X180714Y140968D01*
X159815D01*
X146410Y154373D01*
Y160408D01*
X144829Y161989D01*
X143770D01*
X142950Y162809D01*
Y163969D01*
X143770Y164789D01*
X144829D01*
X146410Y166370D01*
Y168608D01*
X144829Y170189D01*
X143770D01*
X142950Y171009D01*
Y172169D01*
X143770Y172989D01*
X144829D01*
X146410Y174570D01*
Y176808D01*
X144829Y178389D01*
X143770D01*
X142950Y179209D01*
Y180369D01*
X143770Y181189D01*
X144829D01*
X146410Y182770D01*
Y185008D01*
X144829Y186589D01*
X143770D01*
X142950Y187409D01*
Y188569D01*
X143770Y189389D01*
X144829D01*
X146410Y190970D01*
Y193208D01*
X144829Y194789D01*
X143770D01*
X142950Y195609D01*
Y196769D01*
X143770Y197589D01*
X144829D01*
X146410Y199170D01*
Y201408D01*
X144829Y202989D01*
X143770D01*
X142950Y203809D01*
Y204969D01*
X143770Y205789D01*
X144829D01*
X146410Y207370D01*
Y210808D01*
X156352Y220750D01*
X165828D01*
X170162Y225084D01*
X175573D01*
G01X181393Y223784D02*
X178255Y220646D01*
X172290D01*
X168168Y216524D01*
X158862D01*
X150670Y208332D01*
Y155896D01*
X161012Y145554D01*
X162172D01*
X162992Y146374D01*
Y147534D01*
X154001Y156525D01*
Y157685D01*
X154821Y158505D01*
X155981D01*
X169422Y145064D01*
X182634D01*
X200440Y127258D01*
Y120759D01*
X199620Y119939D01*
X197460D01*
X196640Y119119D01*
Y117959D01*
X197460Y117139D01*
X199620D01*
X200440Y116319D01*
Y114187D01*
X197850Y111597D01*
Y106978D01*
X196512Y105640D01*
X196493D01*
Y105637D01*
G01X184166Y222517D02*
X177537Y215888D01*
X176379D01*
X174304Y217964D01*
X173146D01*
X172324Y217142D01*
Y215984D01*
X174399Y213908D01*
Y212750D01*
X172841Y211192D01*
X171014D01*
X169070Y213136D01*
X167922D01*
X158082Y203296D01*
X157234D01*
X156102Y204428D01*
Y205276D01*
X162867Y212041D01*
Y213201D01*
X162047Y214021D01*
X160887D01*
X153170Y206304D01*
Y164860D01*
X160888Y157142D01*
X162048D01*
X163407Y158501D01*
X164567D01*
X165387Y157681D01*
Y156521D01*
X164028Y155162D01*
Y154002D01*
X164848Y153182D01*
X166008D01*
X167367Y154541D01*
X168527D01*
X169347Y153721D01*
Y152561D01*
X167988Y151202D01*
Y150042D01*
X170176Y147854D01*
X173268D01*
X174088Y148674D01*
Y149736D01*
X174908Y150556D01*
X176068D01*
X176888Y149736D01*
Y148674D01*
X177708Y147854D01*
X183381D01*
X202940Y128295D01*
Y112585D01*
X200430Y110075D01*
Y104067D01*
X200000Y103637D01*
X199993D01*
G01X220983Y106174D02*
X216409D01*
X214693Y107890D01*
Y112627D01*
X213873Y113447D01*
X212723D01*
X211903Y114267D01*
Y115427D01*
X212723Y116247D01*
X213873D01*
X214693Y117067D01*
Y128936D01*
X184095Y159534D01*
X176169D01*
X167530Y168173D01*
Y184502D01*
X166710Y185322D01*
X165550D01*
X164730Y184502D01*
Y168517D01*
X163910Y167697D01*
X162750D01*
X161930Y168517D01*
Y186425D01*
X196860Y221355D01*
Y224622D01*
G01X187159Y220916D02*
X160838Y194595D01*
X159678D01*
X158858Y195415D01*
Y196575D01*
X169792Y207509D01*
Y208641D01*
X168944Y209489D01*
X167812D01*
X155670Y197347D01*
Y193323D01*
X157070Y191923D01*
Y190611D01*
X155670Y189211D01*
Y165917D01*
X160145Y161442D01*
X165406D01*
X173572Y153276D01*
X181501D01*
X205440Y129337D01*
Y105563D01*
X203153Y103276D01*
Y97137D01*
X200463Y94447D01*
X198243D01*
X196653Y92857D01*
Y91837D01*
G01X201820Y224307D02*
Y219215D01*
X179650Y197045D01*
Y195342D01*
X178436Y194128D01*
X176733D01*
X174100Y191495D01*
Y175793D01*
X174900Y174993D01*
X176100D01*
X176900Y175793D01*
Y189789D01*
X177720Y190609D01*
X178880D01*
X179700Y189789D01*
Y171017D01*
X220913Y129804D01*
Y119137D01*
X224285Y115765D01*
X226554D01*
X227333Y114986D01*
Y105669D01*
X228940Y104062D01*
Y102769D01*
X227333Y101162D01*
Y99869D01*
X228940Y98262D01*
Y96969D01*
X227333Y95362D01*
Y93521D01*
X229307Y91547D01*
X231013D01*
G01X222983Y91587D02*
X223729Y92333D01*
Y101776D01*
X224370Y102417D01*
Y103808D01*
X224373D01*
Y111877D01*
X222154Y114096D01*
X220994D01*
X219319Y112421D01*
X218159D01*
X217339Y113241D01*
Y114401D01*
X219014Y116076D01*
Y117236D01*
X218410Y117840D01*
Y128758D01*
X174862Y172306D01*
X173702D01*
X172882Y171486D01*
Y170326D01*
X179193Y164015D01*
Y162855D01*
X178373Y162035D01*
X177213D01*
X170037Y169211D01*
X170030D01*
Y190980D01*
X199470Y220420D01*
Y224842D01*
G01X233138Y125802D02*
X231370Y127570D01*
Y130380D01*
X194380Y167370D01*
Y189385D01*
X195201Y190206D01*
X196359D01*
X197180Y189385D01*
Y171855D01*
X198761Y170274D01*
X200999D01*
X202580Y171855D01*
Y187391D01*
X203030Y187841D01*
Y189431D01*
X202580Y189881D01*
Y192191D01*
X203030Y192641D01*
Y194231D01*
X202580Y194681D01*
Y197327D01*
X209564Y204311D01*
Y206549D01*
X207983Y208130D01*
X205745D01*
X195090Y197475D01*
X193930D01*
X193107Y198297D01*
Y199456D01*
X209540Y215889D01*
Y223796D01*
G01X204190Y223552D02*
Y218040D01*
X182200Y196050D01*
Y174166D01*
X183020Y173346D01*
X184180D01*
X185000Y174166D01*
Y194788D01*
X185820Y195608D01*
X186980D01*
X187800Y194788D01*
Y171549D01*
X185970Y169719D01*
Y168284D01*
X223530Y130724D01*
Y127392D01*
X223533D01*
Y120287D01*
X225433Y118387D01*
X231035D01*
X231953Y117469D01*
Y115655D01*
X230530Y114232D01*
Y112986D01*
X231953Y111563D01*
Y109807D01*
X230643Y108497D01*
G01X228138Y125802D02*
X230070Y127734D01*
Y129841D01*
X193080Y166831D01*
Y189924D01*
X194662Y191506D01*
X196898D01*
X198480Y189924D01*
Y172394D01*
X199300Y171574D01*
X200460D01*
X201280Y172394D01*
Y197866D01*
X208264Y204850D01*
Y206010D01*
X207444Y206830D01*
X206284D01*
X195629Y196175D01*
X193391D01*
X191807Y197758D01*
Y199995D01*
X208240Y216428D01*
Y223796D01*
G01X233083Y94817D02*
X231740Y96160D01*
Y101940D01*
X234110Y104310D01*
Y107344D01*
X234883Y108117D01*
Y112383D01*
X234880D01*
Y120577D01*
X237780Y123477D01*
Y129820D01*
X213600Y154000D01*
X213602D01*
X212170Y155432D01*
Y157789D01*
X211365Y158594D01*
X209008D01*
X207790Y159812D01*
Y160972D01*
X208610Y161792D01*
X211110D01*
X211910Y162592D01*
Y163792D01*
X211110Y164592D01*
X205500D01*
X204680Y165412D01*
Y166572D01*
X205500Y167392D01*
X210730D01*
X211530Y168192D01*
Y169392D01*
X210730Y170192D01*
X207790D01*
X206970Y171012D01*
Y172172D01*
X207790Y172992D01*
X210300D01*
X211120Y173812D01*
Y174972D01*
X210300Y175792D01*
X209490D01*
X208670Y176612D01*
Y177772D01*
X209490Y178592D01*
X210820D01*
X211640Y179412D01*
Y180572D01*
X210820Y181392D01*
X209640D01*
X208820Y182212D01*
Y183372D01*
X209640Y184192D01*
X211280D01*
X212100Y185012D01*
Y186172D01*
X211280Y186992D01*
X210050D01*
X209230Y187812D01*
Y188972D01*
X210050Y189792D01*
X211380D01*
X212200Y190612D01*
Y191772D01*
X211380Y192592D01*
X208040D01*
X207220Y193412D01*
Y194572D01*
X208040Y195392D01*
X212780D01*
X213600Y196212D01*
Y198039D01*
X212040Y199599D01*
Y200552D01*
X213600Y202112D01*
Y224555D01*
G01X221100Y227103D02*
Y202261D01*
X224110Y199251D01*
Y196865D01*
X226960Y194015D01*
Y190791D01*
X225640Y189471D01*
Y154541D01*
X246530Y133651D01*
Y112599D01*
X247340Y111789D01*
X252010D01*
X253999Y113778D01*
Y113769D01*
X261015D01*
X261590Y113194D01*
Y110735D01*
X260927Y110072D01*
X260330D01*
X259610Y109352D01*
Y104718D01*
X260430Y103898D01*
X260920D01*
X261740Y103078D01*
Y101918D01*
X260920Y101098D01*
X260430D01*
X259610Y100278D01*
Y97203D01*
X258842Y96435D01*
X255670D01*
X251944Y100161D01*
X249229D01*
X243310Y94242D01*
Y92156D01*
X240620Y89466D01*
Y86751D01*
X239472Y85603D01*
Y85601D01*
X235540D01*
X234172Y86969D01*
Y90366D01*
X235113Y91307D01*
G01X234243Y100156D02*
X237087D01*
X237887Y99356D01*
Y95707D01*
X238736Y94858D01*
X239938D01*
X240787Y95707D01*
Y98830D01*
X241636Y99679D01*
X244719D01*
X248035Y102995D01*
X255185D01*
X256260Y104070D01*
Y107906D01*
X255417Y108749D01*
X244820D01*
X243890Y109679D01*
Y111024D01*
X243041Y111873D01*
X241190D01*
X240390Y112673D01*
Y113973D01*
X241190Y114773D01*
X243041D01*
X243890Y115622D01*
Y116824D01*
X243041Y117673D01*
X242419D01*
X241570Y118522D01*
Y119724D01*
X242419Y120573D01*
X243041D01*
X243890Y121422D01*
Y131707D01*
X223100Y152497D01*
Y190469D01*
X224458Y191827D01*
Y192979D01*
X223638Y193799D01*
X222478D01*
Y193807D01*
X221013Y192342D01*
X219500D01*
X218600Y193242D01*
Y195260D01*
X219420Y196080D01*
X220780D01*
X221600Y196900D01*
Y198060D01*
X220780Y198880D01*
X219420D01*
X218600Y199700D01*
Y226631D01*
G01X216100Y226599D02*
Y192191D01*
X220430Y187861D01*
Y158603D01*
X219630Y157803D01*
X218430D01*
X217630Y158603D01*
Y186254D01*
X216810Y187074D01*
X215650D01*
X214830Y186254D01*
Y156552D01*
X240820Y130562D01*
Y122706D01*
X237770Y119656D01*
Y103607D01*
X237773D01*
G01X291927Y102991D02*
X293790Y104854D01*
Y106973D01*
X294600Y107783D01*
Y111893D01*
X290370Y116123D01*
Y124151D01*
X289924Y124597D01*
X287334D01*
X285993Y125938D01*
Y135241D01*
X287574Y136822D01*
X289900D01*
X290700Y137622D01*
Y138822D01*
X289900Y139622D01*
X287574D01*
X285993Y141203D01*
Y143441D01*
X287574Y145022D01*
X291450D01*
X292270Y145842D01*
Y147002D01*
X291450Y147822D01*
X287574D01*
X285993Y149403D01*
Y152856D01*
X290100Y156963D01*
Y161456D01*
X288728Y162828D01*
X283921D01*
X282360Y164389D01*
Y166667D01*
X283921Y168228D01*
X288050D01*
X288870Y169048D01*
Y172289D01*
X283664Y177495D01*
X282506D01*
X280221Y175210D01*
X278011D01*
X276402Y176819D01*
Y179029D01*
X278687Y181314D01*
Y182472D01*
X275961Y185198D01*
X274204D01*
X270670Y188732D01*
Y190488D01*
X245500Y215659D01*
Y247163D01*
X240447Y252216D01*
Y255269D01*
X241867Y256689D01*
X243209D01*
X243862Y257342D01*
Y257931D01*
G01X296927Y102991D02*
X295090Y104828D01*
Y106434D01*
X295900Y107244D01*
Y112432D01*
X291670Y116662D01*
Y124690D01*
X290463Y125897D01*
X287873D01*
X287293Y126477D01*
Y134702D01*
X288113Y135522D01*
X290439D01*
X292000Y137083D01*
Y139361D01*
X290439Y140922D01*
X288113D01*
X287293Y141742D01*
Y142902D01*
X288113Y143722D01*
X291989D01*
X293570Y145303D01*
Y147541D01*
X291989Y149122D01*
X288113D01*
X287293Y149942D01*
Y152317D01*
X291400Y156424D01*
Y161995D01*
X289267Y164128D01*
X284460D01*
X283660Y164928D01*
Y166128D01*
X284460Y166928D01*
X288589D01*
X290170Y168509D01*
Y172828D01*
X284203Y178795D01*
X281967D01*
X279682Y176510D01*
X278550D01*
X277702Y177358D01*
Y178490D01*
X279987Y180775D01*
Y183011D01*
X276500Y186498D01*
X274743D01*
X271970Y189271D01*
Y191027D01*
X246800Y216198D01*
Y247702D01*
X241747Y252755D01*
Y254730D01*
X242406Y255389D01*
X243748D01*
X245162Y256803D01*
Y257931D01*
G01X251470Y263053D02*
Y256217D01*
X247983Y252730D01*
Y250015D01*
X249942Y248056D01*
X259480D01*
X260080Y247456D01*
Y245367D01*
X259480Y244767D01*
X253059D01*
X250800Y242508D01*
Y217858D01*
X273594Y195064D01*
X275831D01*
X276660Y195893D01*
X277817D01*
X278642Y195068D01*
Y193912D01*
X277813Y193083D01*
Y190845D01*
X279395Y189263D01*
X281632D01*
X282461Y190092D01*
X283618D01*
X284443Y189267D01*
Y188111D01*
X283614Y187282D01*
Y185044D01*
X298140Y170518D01*
Y136787D01*
X296550Y135197D01*
Y128038D01*
X295770Y127258D01*
Y118701D01*
X299420Y115051D01*
Y102048D01*
X297830Y100458D01*
Y96103D01*
X298773Y95160D01*
Y93975D01*
X296870Y92072D01*
G01X252770Y263053D02*
Y255678D01*
X249283Y252191D01*
Y250554D01*
X250481Y249356D01*
X260019D01*
X261380Y247995D01*
Y244828D01*
X260019Y243467D01*
X253598D01*
X252100Y241969D01*
Y218397D01*
X274133Y196364D01*
X275291D01*
X276121Y197194D01*
X278357Y197193D01*
X279943Y195607D01*
X279942Y193373D01*
X279113Y192544D01*
Y191384D01*
X279934Y190563D01*
X281092D01*
X281922Y191393D01*
X284158Y191392D01*
X285744Y189806D01*
X285743Y187572D01*
X284914Y186743D01*
Y185583D01*
X299440Y171057D01*
Y136248D01*
X297850Y134658D01*
Y127499D01*
X297070Y126719D01*
Y119240D01*
X300720Y115590D01*
Y101509D01*
X299130Y99919D01*
Y96642D01*
X300073Y95699D01*
Y93869D01*
X301870Y92072D01*
G01X271133Y92787D02*
X271893Y92027D01*
X273323D01*
X274503Y90847D01*
Y87267D01*
X277573Y84197D01*
X301901D01*
X305370Y87666D01*
Y95480D01*
X305930Y96040D01*
Y127583D01*
X306030Y127683D01*
Y163369D01*
X303600Y165799D01*
Y178290D01*
X279206Y202684D01*
X273606D01*
X256492Y219798D01*
Y222466D01*
G01X255287Y226709D02*
Y226702D01*
X256652D01*
X259600Y223754D01*
Y220235D01*
X274645Y205190D01*
X280236D01*
X306300Y179126D01*
Y166972D01*
X309000Y164272D01*
Y134480D01*
X309890Y133590D01*
Y128006D01*
X308430Y126546D01*
Y87179D01*
X302848Y81597D01*
X276587D01*
X271910Y86274D01*
Y89250D01*
X272245Y89585D01*
G01X268160Y225138D02*
Y223229D01*
X269828Y221561D01*
X270988D01*
X273788Y224361D01*
X274948D01*
X281344Y217967D01*
Y216809D01*
X280522Y215987D01*
X279363D01*
X274948Y220401D01*
X273788D01*
X272968Y219581D01*
Y218421D01*
X278230Y213159D01*
X285007D01*
X287840Y210326D01*
X291153D01*
X296442Y205037D01*
X299767D01*
X320833Y183971D01*
Y183053D01*
X321653Y182233D01*
X322640D01*
X323460Y181413D01*
Y180253D01*
X322640Y179433D01*
X321653D01*
X320833Y178613D01*
Y157489D01*
X321653Y156669D01*
X322560D01*
X323380Y155849D01*
Y154689D01*
X322560Y153869D01*
X321653D01*
X320833Y153049D01*
Y134377D01*
X318483Y132027D01*
Y128159D01*
X319710Y126932D01*
Y120959D01*
X316630Y117879D01*
Y104106D01*
X317850Y102886D01*
Y96081D01*
X317970Y95961D01*
G01X269963Y227380D02*
X275480D01*
X284740Y218120D01*
Y217132D01*
X288230Y213642D01*
X291508D01*
X297326Y207824D01*
X301349D01*
X327470Y181703D01*
Y178697D01*
X326650Y177877D01*
X324660D01*
X323840Y177057D01*
Y175897D01*
X324660Y175077D01*
X326650D01*
X327470Y174257D01*
Y173097D01*
X326650Y172277D01*
X324660D01*
X323840Y171457D01*
Y170297D01*
X324660Y169477D01*
X326650D01*
X327470Y168657D01*
Y167497D01*
X326650Y166677D01*
X324660D01*
X323840Y165857D01*
Y164697D01*
X324660Y163877D01*
X326650D01*
X327470Y163057D01*
Y161897D01*
X326650Y161077D01*
X324660D01*
X323840Y160257D01*
Y159097D01*
X324660Y158277D01*
X326650D01*
X327470Y157457D01*
Y154874D01*
X323533Y150937D01*
Y135337D01*
X324883Y133987D01*
Y132569D01*
X324063Y131749D01*
X321923D01*
X321103Y130929D01*
Y129769D01*
X321923Y128949D01*
X324063D01*
X324883Y128129D01*
Y126017D01*
X325960Y124940D01*
Y122124D01*
X324074Y120238D01*
X323251D01*
X319130Y116117D01*
Y105142D01*
X320740Y103532D01*
Y98599D01*
G01X272503Y251033D02*
X276706Y246830D01*
X278936D01*
X280280Y245486D01*
Y243355D01*
X300387Y223248D01*
X303663D01*
X340167Y186744D01*
X340140Y186717D01*
Y174174D01*
X340960Y173354D01*
X342120D01*
X342940Y174174D01*
Y178939D01*
X343760Y179759D01*
X344920D01*
X345740Y178939D01*
Y150300D01*
X338720Y143280D01*
Y119796D01*
X340939Y117577D01*
X345698D01*
X346813Y116462D01*
Y96787D01*
X344873Y94847D01*
G01X272035Y248397D02*
X275890Y244542D01*
Y243166D01*
X278382Y240674D01*
X279419D01*
X299350Y220743D01*
X302626D01*
X336220Y187149D01*
Y169201D01*
X337040Y168381D01*
X341000D01*
X341820Y167561D01*
Y155378D01*
X341020Y154578D01*
X339820D01*
X339020Y155378D01*
Y164761D01*
X338200Y165581D01*
X337040D01*
X336220Y164761D01*
Y118297D01*
X344253Y110264D01*
Y105717D01*
X340450Y101914D01*
G01X365283Y128125D02*
X365291D01*
X370130Y132964D01*
Y135842D01*
X371570Y137282D01*
Y138642D01*
X370130Y140082D01*
Y142061D01*
X370950Y142881D01*
X372130D01*
X372950Y143701D01*
Y144861D01*
X372130Y145681D01*
X370950D01*
X370130Y146501D01*
Y147661D01*
X370950Y148481D01*
X372130D01*
X372950Y149301D01*
Y150461D01*
X372130Y151281D01*
X370950D01*
X370130Y152101D01*
Y153261D01*
X370950Y154081D01*
X372130D01*
X372950Y154901D01*
Y156061D01*
X372130Y156881D01*
X370950D01*
X370130Y157701D01*
Y158861D01*
X370950Y159681D01*
X372130D01*
X372950Y160501D01*
Y161661D01*
X372130Y162481D01*
X370950D01*
X370130Y163301D01*
Y164461D01*
X370950Y165281D01*
X372130D01*
X372950Y166101D01*
Y167261D01*
X372130Y168081D01*
X370950D01*
X370130Y168901D01*
Y170061D01*
X370950Y170881D01*
X372130D01*
X372950Y171701D01*
Y172861D01*
X372130Y173681D01*
X370950D01*
X370130Y174501D01*
Y175661D01*
X370950Y176481D01*
X372130D01*
X372950Y177301D01*
Y178461D01*
X372130Y179281D01*
X370950D01*
X370130Y180101D01*
Y181261D01*
X370950Y182081D01*
X372130D01*
X372950Y182901D01*
Y184061D01*
X372130Y184881D01*
X370950D01*
X370130Y185701D01*
Y186861D01*
X370950Y187681D01*
X372130D01*
X372950Y188501D01*
Y189661D01*
X372130Y190481D01*
X370950D01*
X370130Y191301D01*
Y196330D01*
X323818Y242642D01*
X309964D01*
X305930Y246676D01*
Y254181D01*
X303188Y256923D01*
G01X354448Y108092D02*
Y110344D01*
X354982Y110878D01*
X358290D01*
X359090Y111678D01*
Y113336D01*
X358290Y114136D01*
X353200D01*
X352380Y114956D01*
Y116116D01*
X353200Y116936D01*
X356331D01*
X357151Y117756D01*
Y120002D01*
X356331Y120822D01*
X353390D01*
X352570Y121642D01*
Y122802D01*
X353390Y123622D01*
X356331D01*
X357151Y124442D01*
Y128979D01*
X359048Y130876D01*
Y132036D01*
X357075Y134009D01*
Y135169D01*
X357895Y135989D01*
X359055D01*
X361028Y134016D01*
X362188D01*
X363850Y135678D01*
Y176585D01*
X365130Y177865D01*
Y179385D01*
X363850Y180665D01*
Y182185D01*
X365130Y183465D01*
Y184985D01*
X363850Y186265D01*
Y187785D01*
X365130Y189065D01*
Y190585D01*
X363850Y191865D01*
Y195409D01*
X321623Y237636D01*
X307634D01*
X304030Y241240D01*
Y241293D01*
X300189Y245134D01*
X297692D01*
X293940Y248886D01*
Y255263D01*
X290572Y258631D01*
X288775D01*
G01X272841Y253312D02*
X273435D01*
X277336Y249411D01*
X280297D01*
X283990Y245718D01*
Y243323D01*
X301561Y225752D01*
X304713D01*
X329783Y200682D01*
X330943D01*
X331651Y201390D01*
X332811D01*
X333631Y200570D01*
Y199410D01*
X332923Y198702D01*
Y197542D01*
X335071Y195394D01*
X342993D01*
X350750Y187636D01*
Y186466D01*
X350759D01*
X349938Y185645D01*
X348781D01*
X342531Y191895D01*
X341372D01*
X340551Y191074D01*
Y189914D01*
X351570Y178895D01*
Y177647D01*
X350750Y176827D01*
X349060D01*
X348240Y176007D01*
Y174847D01*
X349060Y174027D01*
X350750D01*
X351570Y173207D01*
Y172047D01*
X350750Y171227D01*
X349060D01*
X348240Y170407D01*
Y169247D01*
X349060Y168427D01*
X350750D01*
X351570Y167607D01*
Y166447D01*
X350750Y165627D01*
X349060D01*
X348240Y164807D01*
Y163647D01*
X349060Y162827D01*
X350750D01*
X351570Y162007D01*
Y160847D01*
X350750Y160027D01*
X349060D01*
X348240Y159207D01*
Y158047D01*
X349060Y157227D01*
X350750D01*
X351570Y156407D01*
Y150690D01*
X341220Y140340D01*
Y123487D01*
X343740Y120967D01*
X343743D01*
G01X292341Y244614D02*
X304698Y232257D01*
X319500D01*
X323051Y228704D01*
Y227546D01*
X318945Y223442D01*
X318944Y221207D01*
X332149Y207995D01*
X334387D01*
X335971Y209577D01*
Y211815D01*
X326049Y221743D01*
Y222901D01*
X326871Y223723D01*
X328030Y223722D01*
X358550Y193185D01*
Y188800D01*
X358070Y188320D01*
Y185920D01*
X358550Y185440D01*
Y182320D01*
X358070Y181840D01*
Y179440D01*
X358550Y178960D01*
Y143329D01*
X356585Y141364D01*
X351455D01*
X347720Y137629D01*
Y130405D01*
X349295Y128830D01*
X350627D01*
X351485Y127972D01*
X351503D01*
G01X345463Y90837D02*
X349643Y95017D01*
Y122421D01*
X343720Y128344D01*
Y139291D01*
X354070Y149641D01*
Y191994D01*
X339641Y206423D01*
X338481D01*
X337661Y205603D01*
Y204443D01*
X342222Y199882D01*
Y198722D01*
X341402Y197902D01*
X340242D01*
X334152Y203992D01*
X330012D01*
X314071Y219933D01*
Y221093D01*
X314799Y221821D01*
Y222981D01*
X313979Y223801D01*
X312819D01*
X312091Y223073D01*
X310931D01*
X310111Y223893D01*
Y225053D01*
X311335Y226277D01*
Y227437D01*
X310515Y228257D01*
X309355D01*
X308131Y227033D01*
X306971D01*
X305747Y228257D01*
X303772D01*
X291335Y240694D01*
X290699D01*
X288030Y243363D01*
Y247042D01*
X285607Y249465D01*
X283133D01*
X280526Y252072D01*
G01X293261Y245534D02*
X305238Y233557D01*
X320039D01*
X324351Y229243D01*
Y227007D01*
X320245Y222903D01*
Y221745D01*
X332688Y209295D01*
X333849D01*
X334671Y210116D01*
Y211276D01*
X324749Y221204D01*
Y223440D01*
X326333Y225024D01*
X328569Y225022D01*
X359850Y193724D01*
Y142790D01*
X357124Y140064D01*
X351994D01*
X349020Y137090D01*
Y130944D01*
X349834Y130130D01*
X350654D01*
X351496Y130972D01*
X351503D01*
G01X358343Y90948D02*
Y93107D01*
X359622Y94386D01*
X360818D01*
X365950Y99518D01*
Y103370D01*
X369120Y106540D01*
Y111114D01*
X373470Y115464D01*
Y130539D01*
X375450Y132519D01*
Y194551D01*
X324817Y245184D01*
X310279D01*
X308986Y246477D01*
Y252895D01*
X308980Y252901D01*
Y255286D01*
X304810Y259456D01*
G01X302056Y254852D02*
X302880Y254028D01*
Y245873D01*
X308611Y240142D01*
X322782D01*
X367630Y195294D01*
Y173424D01*
X366470Y172264D01*
Y170624D01*
X367630Y169464D01*
Y167824D01*
X366470Y166664D01*
Y165024D01*
X367630Y163864D01*
Y162224D01*
X366470Y161064D01*
Y159424D01*
X367630Y158264D01*
Y156624D01*
X366470Y155464D01*
Y153824D01*
X367630Y152664D01*
Y151024D01*
X366470Y149864D01*
Y148224D01*
X367630Y147064D01*
Y145424D01*
X366470Y144264D01*
Y142624D01*
X367630Y141464D01*
Y135784D01*
X359850Y128004D01*
Y118739D01*
X363940Y114649D01*
Y106854D01*
X362505Y105419D01*
X359426D01*
X358050Y104043D01*
Y101431D01*
X353713Y97094D01*
Y93057D01*
G54D15*
X712975Y155655D03*
Y234461D03*
X723275Y155655D03*
Y234461D03*
G54D25*
G01X225570Y230256D02*
Y207749D01*
X238080Y195239D01*
Y184781D01*
X237231Y183932D01*
X235689D01*
X234840Y183083D01*
Y181881D01*
X235689Y181032D01*
X237231D01*
X238080Y180183D01*
Y178981D01*
X237231Y178132D01*
X235689D01*
X234840Y177283D01*
Y176081D01*
X235689Y175232D01*
X237231D01*
X238080Y174383D01*
Y173181D01*
X237231Y172332D01*
X235689D01*
X234840Y171483D01*
Y170281D01*
X235689Y169432D01*
X237231D01*
X238080Y168583D01*
Y167381D01*
X237231Y166532D01*
X235689D01*
X234840Y165683D01*
Y164481D01*
X235689Y163632D01*
X237231D01*
X238080Y162783D01*
Y151511D01*
X253530Y136061D01*
Y133878D01*
X254379Y133029D01*
X258870D01*
X259670Y132229D01*
Y130929D01*
X258870Y130129D01*
X254379D01*
X253530Y129280D01*
Y128078D01*
X254379Y127229D01*
X255491D01*
X256340Y126380D01*
Y125178D01*
X255491Y124329D01*
X254379D01*
X253530Y123480D01*
Y120175D01*
X255054Y118651D01*
X263981D01*
X264660Y117972D01*
Y117871D01*
X266750Y115781D01*
Y106008D01*
X268780Y103978D01*
X268627D01*
X268770Y103835D01*
Y98518D01*
X272541Y94747D01*
X280703D01*
X282933Y92517D01*
Y89257D01*
X282145Y88469D01*
X280211D01*
X279243Y89437D01*
Y90599D01*
X277723Y92119D01*
X276603D01*
G01X226010Y233542D02*
X228170Y231382D01*
Y208830D01*
X241010Y195990D01*
Y153104D01*
X257295Y136819D01*
X258495D01*
X259346Y137670D01*
Y138870D01*
X244045Y154171D01*
Y155373D01*
X244894Y156222D01*
X246096D01*
X262510Y139808D01*
Y127596D01*
X265069Y125036D01*
X267020Y123085D01*
Y119188D01*
X271380Y114828D01*
Y100238D01*
X273973Y97645D01*
G01X281200Y98369D02*
X276993D01*
X274160Y101202D01*
Y116397D01*
X271490Y119067D01*
Y127887D01*
X270890Y128487D01*
X266340D01*
X265740Y129087D01*
Y149260D01*
X248786Y166214D01*
X247586Y166213D01*
X246736Y165363D01*
X246737Y164161D01*
X260792Y150106D01*
Y148974D01*
X259873Y148055D01*
X258741D01*
X243610Y163186D01*
Y197075D01*
X230770Y209915D01*
Y232615D01*
X229820Y233565D01*
Y235257D01*
X233820Y239257D01*
Y241152D01*
X236710Y244042D01*
G01X278760Y101061D02*
X276760Y103061D01*
Y117674D01*
X274140Y120294D01*
Y152702D01*
X273291Y153551D01*
X272089D01*
X271240Y152702D01*
Y131845D01*
X270640Y131245D01*
X268940D01*
X268340Y131845D01*
Y153381D01*
X267800Y153921D01*
X264769D01*
X246210Y172480D01*
Y198152D01*
X233650Y210712D01*
Y233345D01*
X232948Y234047D01*
G01X293505Y94965D02*
Y94967D01*
X293510D01*
Y96157D01*
X288970Y100697D01*
Y104046D01*
X290350Y105426D01*
Y110346D01*
X286320Y114376D01*
Y119410D01*
X281940Y123790D01*
Y159039D01*
X278528Y162451D01*
X273139D01*
X272290Y163300D01*
Y166638D01*
X273139Y167487D01*
X277820D01*
X278620Y168287D01*
Y169587D01*
X277820Y170387D01*
X273139D01*
X272290Y171236D01*
Y181206D01*
X271490Y182006D01*
X270190D01*
X269390Y181206D01*
Y169122D01*
X268541Y168273D01*
X267339D01*
X266490Y169122D01*
Y188937D01*
X241450Y213977D01*
Y236581D01*
X242460Y237591D01*
G01X289720Y96094D02*
X286370Y99444D01*
Y101283D01*
X284603Y103050D01*
Y112376D01*
X283240Y113739D01*
Y118711D01*
X279340Y122611D01*
Y156916D01*
X276732Y159524D01*
X269353D01*
X268566Y160311D01*
Y161511D01*
X269608Y162553D01*
Y163753D01*
X268757Y164604D01*
X267557D01*
X266515Y163562D01*
X265315D01*
X263500Y165377D01*
Y187957D01*
X262651Y188806D01*
X261449D01*
X260600Y187957D01*
Y169898D01*
X259751Y169049D01*
X258549D01*
X257700Y169898D01*
Y194049D01*
X238850Y212899D01*
Y238069D01*
X241750Y240969D01*
Y246717D01*
X238748Y249719D01*
X237654D01*
G01X237594Y252754D02*
X234960Y250120D01*
Y247585D01*
X235635Y246910D01*
X237757D01*
X239150Y245517D01*
Y241747D01*
X236250Y238847D01*
Y211803D01*
X249300Y198753D01*
Y173072D01*
X250149Y172223D01*
X251351D01*
X252200Y173072D01*
Y192966D01*
X253049Y193815D01*
X254251D01*
X255100Y192966D01*
Y168818D01*
X266995Y156923D01*
X273650D01*
X276740Y153833D01*
Y121444D01*
X280120Y118064D01*
Y112239D01*
X281543Y110816D01*
Y102099D01*
X283830Y99812D01*
Y95450D01*
X287423Y91857D01*
G01X312223Y96407D02*
X312700Y96884D01*
Y100752D01*
X310980Y102472D01*
Y125489D01*
X312630Y127139D01*
Y162018D01*
X315320Y164708D01*
Y179541D01*
X314520Y180341D01*
X313220D01*
X312420Y179541D01*
Y168788D01*
X311620Y167988D01*
X310320D01*
X309520Y168788D01*
Y182810D01*
X296681Y195649D01*
X293906D01*
X281557Y207998D01*
X275631D01*
X262230Y221399D01*
Y225139D01*
X257589Y229780D01*
X255021D01*
X254221Y230580D01*
Y230582D01*
G01X311553Y92347D02*
X312463Y93257D01*
Y93451D01*
X315300Y96288D01*
Y101829D01*
X313880Y103249D01*
Y118736D01*
X315570Y120426D01*
Y120429D01*
X315573D01*
X316580Y121436D01*
Y124910D01*
X316617Y124947D01*
X315763Y125801D01*
Y134447D01*
X318173Y136857D01*
Y143834D01*
X317324Y144683D01*
X316659D01*
X315810Y145532D01*
Y146734D01*
X316659Y147583D01*
X317324D01*
X318173Y148432D01*
Y149634D01*
X317324Y150483D01*
X316659D01*
X315810Y151332D01*
Y152534D01*
X316659Y153383D01*
X317324D01*
X318173Y154232D01*
Y155434D01*
X317324Y156283D01*
X316659D01*
X315810Y157132D01*
Y158334D01*
X316659Y159183D01*
X317324D01*
X318173Y160032D01*
Y182324D01*
X316074Y184423D01*
X314874D01*
X313975Y183524D01*
X312775D01*
X311924Y184375D01*
Y185575D01*
X312823Y186474D01*
Y187674D01*
X311972Y188525D01*
X310772D01*
X309873Y187626D01*
X308673D01*
X307822Y188477D01*
Y189677D01*
X308721Y190576D01*
Y191776D01*
X307870Y192627D01*
X306670D01*
X305771Y191728D01*
X304571D01*
X303720Y192579D01*
Y193779D01*
X304619Y194678D01*
Y195878D01*
X303768Y196729D01*
X302568D01*
X301669Y195830D01*
X300469D01*
X299618Y196681D01*
Y197881D01*
X300517Y198780D01*
Y199980D01*
X299327Y201170D01*
X297405D01*
X295719Y199484D01*
X294239D01*
X290458Y203265D01*
Y204465D01*
X291233Y205239D01*
Y206439D01*
X290382Y207290D01*
X289182D01*
X288407Y206516D01*
X287207D01*
X283120Y210603D01*
X277116D01*
X265470Y222249D01*
Y224229D01*
G01X269486Y230424D02*
X276054D01*
X289096Y217382D01*
X291382D01*
X297517Y211247D01*
X301550D01*
X330170Y182627D01*
Y153002D01*
X330173Y152999D01*
Y151644D01*
X329324Y150795D01*
X327289D01*
X326440Y149946D01*
Y148744D01*
X327289Y147895D01*
X329324D01*
X330173Y147046D01*
Y145844D01*
X329324Y144995D01*
X327079D01*
X326230Y144146D01*
Y142944D01*
X327079Y142095D01*
X329324D01*
X330173Y141246D01*
Y140044D01*
X329324Y139195D01*
X327079D01*
X326230Y138346D01*
Y137144D01*
X327079Y136295D01*
X329324D01*
X330173Y135446D01*
Y133237D01*
X327474Y130538D01*
Y127134D01*
X328810Y125798D01*
Y121082D01*
X325390Y117662D01*
X324619D01*
X322030Y115073D01*
Y105891D01*
X323520Y104401D01*
Y97762D01*
X318400Y92642D01*
Y91396D01*
X317211Y90207D01*
X315083D01*
G01X303220Y98397D02*
Y132704D01*
X302930Y132994D01*
G54D16*
G01X36848Y25198D02*
Y32018D01*
X36588Y32278D01*
G01X131068Y76588D02*
X122856D01*
X105811Y59543D01*
X77164D01*
X71420Y53799D01*
X45381D01*
X44010Y55170D01*
G01X228821Y274197D02*
Y275421D01*
X227755Y276487D01*
X223103D01*
X221264Y278326D01*
Y281992D01*
X219620Y283636D01*
X201032D01*
X198627Y281231D01*
X157083D01*
X153742Y284572D01*
X135148D01*
X125700Y294020D01*
Y350727D01*
X115310Y361117D01*
X110612D01*
X110230Y360735D01*
G01X231648Y274243D02*
X230421Y275470D01*
Y276084D01*
X228418Y278087D01*
X223766D01*
X222864Y278989D01*
Y282655D01*
X220283Y285236D01*
X200369D01*
X197964Y282831D01*
X157746D01*
X154405Y286172D01*
X135811D01*
X127300Y294683D01*
Y351397D01*
X115980Y362717D01*
X110748D01*
X110230Y363235D01*
G01X180430Y392969D02*
Y393054D01*
X181994Y394618D01*
X184027D01*
X187897Y390748D01*
Y365239D01*
X194621Y358515D01*
Y350752D01*
X193913Y350044D01*
Y342353D01*
X195086Y341180D01*
Y326571D01*
X200211Y321446D01*
G01X200572Y323920D02*
X199717D01*
X196486Y327151D01*
Y341760D01*
X195313Y342933D01*
Y349464D01*
X196221Y350372D01*
Y359178D01*
X189497Y365902D01*
Y391647D01*
X184747Y396397D01*
X182096D01*
X180440Y398053D01*
Y398056D01*
G01X214406Y395539D02*
X209672Y390805D01*
Y371837D01*
X217586Y363923D01*
Y352974D01*
X227425Y343135D01*
Y316455D01*
X229567Y314313D01*
Y304642D01*
X236167Y298042D01*
X239755D01*
X240949Y296848D01*
G01X237799Y303148D02*
X235899Y305048D01*
Y320231D01*
X235245Y320885D01*
Y341625D01*
X225859Y351011D01*
Y363354D01*
X218718Y370495D01*
Y385894D01*
X216009Y388603D01*
X214786D01*
G01X215120Y399654D02*
X215550D01*
X216910Y398294D01*
Y394710D01*
X211990Y389790D01*
Y372888D01*
X219943Y364935D01*
Y352597D01*
X228825Y343715D01*
Y317154D01*
X231481Y314498D01*
X232287D01*
X233867Y312918D01*
Y303930D01*
X234649Y303148D01*
G01X218090Y390891D02*
X218814Y390167D01*
Y388945D01*
X221476Y386283D01*
Y370961D01*
X228889Y363548D01*
Y360679D01*
X230909Y358659D01*
Y350073D01*
X236681Y344301D01*
Y336945D01*
X236645Y336909D01*
Y321465D01*
X238425Y319685D01*
Y314660D01*
X239699Y313386D01*
Y311408D01*
X237799Y309508D01*
Y306298D01*
G01X240949Y303148D02*
X246621Y308820D01*
X250451D01*
X256026Y314395D01*
X256042D01*
X257351Y315704D01*
X263855D01*
X265480Y317329D01*
X306447D01*
X307654Y318536D01*
X328434D01*
X331047Y321149D01*
X347028D01*
X350400Y324521D01*
Y336076D01*
X354422Y340098D01*
X367287D01*
X368880Y341691D01*
Y393460D01*
X356520Y405820D01*
Y415526D01*
X362880Y421886D01*
Y482247D01*
X366130Y485497D01*
Y498901D01*
X370363Y503134D01*
X372500D01*
X374729Y505363D01*
X382149D01*
X389170Y512384D01*
Y554218D01*
X401334Y566382D01*
X454563D01*
X458968Y561977D01*
Y553781D01*
X456991Y551804D01*
X456587D01*
X455678Y551792D01*
X455646D01*
X455595Y551791D01*
X454620D01*
X453917Y551070D01*
Y550069D01*
G01X453854Y555069D02*
Y553937D01*
X454414Y553391D01*
X455579D01*
X455630Y553392D01*
X455667D01*
X456325Y553401D01*
X457368Y554444D01*
Y561314D01*
X453900Y564782D01*
X401997D01*
X390770Y553555D01*
Y511721D01*
X382812Y503763D01*
X375392D01*
X373163Y501534D01*
X371026D01*
X367730Y498238D01*
Y484834D01*
X364480Y481584D01*
Y421223D01*
X358120Y414863D01*
Y406483D01*
X370480Y394123D01*
Y341028D01*
X367950Y338498D01*
X355085D01*
X352000Y335413D01*
Y323858D01*
X347691Y319549D01*
X331710D01*
X329097Y316936D01*
X308317D01*
X307110Y315729D01*
X266143D01*
X264518Y314104D01*
X258014D01*
X257176Y313266D01*
Y313245D01*
X249623Y305692D01*
Y302640D01*
X248181Y301198D01*
X246107D01*
X244118Y303187D01*
G01X402458Y505903D02*
X400287D01*
X399910Y506280D01*
Y506336D01*
X398551Y507695D01*
X398550D01*
Y510179D01*
X399207Y510836D01*
X399210D01*
Y545541D01*
X396590Y548161D01*
Y549310D01*
G01X399590Y553502D02*
Y552011D01*
X401078Y550523D01*
Y550387D01*
X402212Y549253D01*
Y509593D01*
X401556Y508937D01*
G01X406352Y471405D02*
X411552D01*
X424034Y458923D01*
X434032D01*
X441951Y466842D01*
X470894D01*
X475481Y471429D01*
Y517641D01*
X469649Y523473D01*
X460108D01*
X452895Y516260D01*
Y510061D01*
G01X442763Y549595D02*
X445866Y552698D01*
Y558731D01*
X443875Y560722D01*
X410783D01*
X409314Y559253D01*
Y555364D01*
X412395Y552283D01*
Y548774D01*
X410999Y547378D01*
Y543109D01*
X413512Y540596D01*
Y524287D01*
X415930Y521869D01*
Y518409D01*
X414477Y516956D01*
X411439D01*
G54D26*
G01X9240Y638699D02*
Y637075D01*
X6325Y634160D01*
Y397378D01*
X8586Y385649D01*
X11930Y382305D01*
X24132D01*
X44260Y362178D01*
Y359338D01*
X53980Y349618D01*
Y327293D01*
X55170Y319709D01*
Y318436D01*
X55398Y318203D01*
X56509Y311133D01*
X59987Y288969D01*
X60220Y287484D01*
Y229588D01*
X60831Y227019D01*
X64540Y208501D01*
X65136Y207163D01*
X65425Y205721D01*
X70481Y178318D01*
Y176927D01*
X74188Y165568D01*
X92090Y147666D01*
Y131973D01*
X117818Y106245D01*
X124150Y94643D01*
G01X125480Y91163D02*
Y91578D01*
X125875Y91973D01*
Y96010D01*
X125081Y96804D01*
X119670Y106360D01*
X93420Y132610D01*
Y148351D01*
X77921Y163850D01*
X74777Y168776D01*
X71970Y177208D01*
Y194919D01*
X65742Y208883D01*
X61990Y227611D01*
Y259376D01*
X64200Y261586D01*
Y268741D01*
X61470Y282058D01*
Y287617D01*
X56575Y318793D01*
X56420Y318950D01*
Y319807D01*
X55230Y327391D01*
Y350138D01*
X53710Y351659D01*
Y351666D01*
X45510Y359866D01*
Y362700D01*
X23645Y384565D01*
X20460D01*
X19450Y383555D01*
X12450D01*
X9746Y386260D01*
X7700Y396856D01*
Y629404D01*
X7575Y629529D01*
Y632192D01*
X10209Y634826D01*
X13807D01*
G01X9300Y631472D02*
X9155Y631327D01*
Y395916D01*
X10909Y386871D01*
X12975Y384805D01*
X18930D01*
X19940Y385815D01*
X24170D01*
X46762Y363223D01*
Y360385D01*
X54970Y352177D01*
Y352175D01*
X57670Y349465D01*
Y319464D01*
X57753Y319380D01*
X65450Y270364D01*
Y221184D01*
X69154Y204306D01*
X73300Y195018D01*
Y187141D01*
X76570Y176165D01*
Y171906D01*
X79029Y164512D01*
X94890Y148651D01*
Y133077D01*
X122231Y105736D01*
X126568Y97448D01*
X127300Y96716D01*
Y89117D01*
X129580Y86837D01*
G01X11980Y617956D02*
Y612189D01*
X10610Y603138D01*
X10605Y603133D01*
Y590778D01*
X10610Y590773D01*
Y396047D01*
X12181Y387945D01*
X13235Y386891D01*
X14670D01*
X16034Y388255D01*
X23781D01*
X59120Y352916D01*
Y320066D01*
X59360Y318537D01*
Y318536D01*
X59534Y317431D01*
X61855Y302642D01*
X61856Y302641D01*
X64771Y284071D01*
Y284063D01*
X64850Y283565D01*
X67490Y266746D01*
Y225023D01*
X67570Y224787D01*
X70585Y217867D01*
X71207Y215063D01*
X72140Y205624D01*
Y205098D01*
X72785Y202150D01*
X76010Y193340D01*
Y193247D01*
X76107Y193149D01*
X76560Y191208D01*
Y191177D01*
X76635Y190851D01*
X77093Y188897D01*
X78140Y175134D01*
Y171873D01*
X78560Y170613D01*
X83350Y162246D01*
X96350Y149246D01*
Y133771D01*
X123902Y106219D01*
X128330Y98360D01*
G01X15349Y614142D02*
X14090Y611481D01*
Y609009D01*
X11770Y601140D01*
Y401792D01*
X60170Y353392D01*
Y334805D01*
X63443Y299352D01*
X65880Y283784D01*
X65892Y283704D01*
X68540Y266828D01*
Y225453D01*
X68590Y225076D01*
X73035Y214888D01*
X76903Y205243D01*
X77610Y201748D01*
Y191328D01*
X77613Y191319D01*
X77760Y190694D01*
Y190688D01*
X79160Y184721D01*
X79190Y184592D01*
Y172047D01*
X79530Y171047D01*
X83894Y163414D01*
X97400Y149908D01*
Y134802D01*
X126030Y106172D01*
X130055Y98985D01*
Y92855D01*
X129780Y92580D01*
G01X135290Y87664D02*
Y89177D01*
X132760Y93010D01*
Y103510D01*
X132755Y103516D01*
X100250Y136021D01*
Y151020D01*
X87020Y164250D01*
Y172197D01*
X84278Y174939D01*
Y196845D01*
X81280Y199843D01*
Y214472D01*
X77790Y217962D01*
Y224194D01*
X72759Y229225D01*
Y266922D01*
X80098Y274261D01*
Y282652D01*
X79230Y283520D01*
Y321530D01*
X63110Y337650D01*
Y354276D01*
X14475Y402911D01*
Y567641D01*
X15290Y568456D01*
Y597153D01*
X14500Y601957D01*
G01X20350Y555807D02*
X17250Y552707D01*
Y404174D01*
X47718Y373706D01*
X53116D01*
X66130Y360692D01*
Y339067D01*
X84325Y320872D01*
Y266897D01*
X78964Y261536D01*
Y253946D01*
X78100Y253082D01*
Y244892D01*
X75860Y242652D01*
Y230084D01*
X80930Y225014D01*
Y219200D01*
X84080Y216050D01*
Y200583D01*
X86778Y197884D01*
Y176764D01*
X89520Y174022D01*
Y165292D01*
X103020Y151792D01*
Y137124D01*
X135520Y104624D01*
Y93370D01*
X142880Y82227D01*
X144060Y80445D01*
X144134Y80316D01*
X149823Y74627D01*
X152185D01*
X155208Y71604D01*
X209506D01*
X219858Y61252D01*
X250141D01*
X251510Y59883D01*
X260123D01*
X265315Y54691D01*
X312859D01*
X343937Y42880D01*
X344320Y42494D01*
X357960D01*
X359430Y43964D01*
X441380D01*
X445860Y48444D01*
X467982D01*
X471541Y52003D01*
X489200D01*
X534930Y97733D01*
Y101680D01*
X542071Y108821D01*
X544934D01*
X546306Y110193D01*
G01X13510Y591939D02*
X13220Y591649D01*
Y402398D01*
X61860Y353758D01*
Y337277D01*
X69110Y305960D01*
Y295294D01*
X69119Y295240D01*
X70070Y269638D01*
Y225311D01*
X78503Y206021D01*
X79190Y203033D01*
Y190978D01*
X80035Y187360D01*
X82760Y175724D01*
Y172839D01*
X85469Y164025D01*
X98850Y150644D01*
Y135509D01*
X127741Y106618D01*
X131510Y99525D01*
Y92634D01*
X132400Y91285D01*
Y88153D01*
G01X140350Y81347D02*
Y83784D01*
X134190Y93113D01*
Y103987D01*
X101500Y136677D01*
Y151541D01*
X88270Y164771D01*
Y172735D01*
X85528Y175477D01*
Y197366D01*
X82830Y200064D01*
Y215156D01*
X79040Y218946D01*
Y224712D01*
X74610Y229146D01*
Y266862D01*
X81348Y273600D01*
Y283685D01*
X80540Y284493D01*
Y321991D01*
X64400Y338131D01*
Y354757D01*
X16000Y403157D01*
Y566721D01*
X16200Y566921D01*
G01X19450Y550297D02*
X18890Y549737D01*
Y404585D01*
X48319Y375156D01*
X53717D01*
X67580Y361293D01*
Y339668D01*
X85775Y321473D01*
Y263854D01*
X83510Y261589D01*
Y256441D01*
X79550Y252481D01*
Y244291D01*
X77310Y242051D01*
Y236936D01*
X79660Y234586D01*
X79940D01*
X82380Y232146D01*
Y219995D01*
X85161Y217214D01*
X85250D01*
X88285Y214179D01*
Y177310D01*
X90970Y174625D01*
Y166078D01*
X104470Y152578D01*
Y137725D01*
X136970Y105225D01*
Y93806D01*
X144090Y83028D01*
X145260Y81266D01*
X145270Y81254D01*
X145303Y81198D01*
X150424Y76077D01*
X152786D01*
X155725Y73138D01*
X210036D01*
X220390Y62784D01*
X250660D01*
X252111Y61333D01*
X260728D01*
X265920Y56141D01*
X314541D01*
X343860Y45001D01*
X344081Y44783D01*
X344083D01*
X344089Y44777D01*
X344930Y43944D01*
X357350D01*
X358820Y45414D01*
X440770D01*
X445250Y49894D01*
X467377D01*
X470936Y53453D01*
X488513D01*
X530730Y95670D01*
Y102402D01*
X539071Y110743D01*
X543613D01*
X545859Y112989D01*
X550490D01*
G01X20650Y546243D02*
Y404310D01*
X48754Y376206D01*
X54158D01*
X68950Y361414D01*
Y340750D01*
X87600Y322100D01*
Y262257D01*
X85830Y260487D01*
Y256488D01*
X81070Y251728D01*
Y235137D01*
X83500Y232707D01*
Y225149D01*
X88400Y220249D01*
X93040Y207187D01*
Y165981D01*
X106110Y152911D01*
Y137789D01*
X138540Y105359D01*
Y93335D01*
X144974Y83607D01*
X146112Y81885D01*
X146116Y81880D01*
X146137Y81849D01*
X150859Y77127D01*
X157279D01*
X159474Y74932D01*
X210296D01*
X221049Y64179D01*
X250516D01*
X251680Y65343D01*
X254368D01*
X256260Y63451D01*
X260100D01*
X266360Y57191D01*
X315628D01*
X343893Y46452D01*
X344343Y46007D01*
X344344D01*
X344560Y45793D01*
X345370Y44994D01*
X356354D01*
X357824Y46464D01*
X439394D01*
X444380Y51450D01*
X467159D01*
X470212Y54503D01*
X487918D01*
X527210Y93795D01*
Y100484D01*
X539607Y112881D01*
X542700D01*
G01X518640Y125539D02*
Y109998D01*
X517900Y109258D01*
Y106029D01*
X518680Y105249D01*
Y89224D01*
X488407Y58951D01*
X483294Y57390D01*
X469263D01*
X466584Y54711D01*
X443500D01*
X421998Y49164D01*
X356700D01*
X355225Y47694D01*
X346490D01*
X345279Y48895D01*
X345277D01*
X345262Y48910D01*
X345025Y49145D01*
X316482Y59994D01*
X267387D01*
X261230Y66151D01*
X257396D01*
X253540Y70007D01*
X226576D01*
X222469Y71286D01*
X212759Y77778D01*
X164952D01*
X158272Y79827D01*
X155629D01*
X151037Y81374D01*
X147077Y85334D01*
X141240Y94160D01*
Y107969D01*
X109000Y140209D01*
Y154652D01*
X95740Y167912D01*
Y208518D01*
X90768Y223192D01*
X87712Y235558D01*
X86674Y243331D01*
Y244815D01*
X87944Y246953D01*
X88950Y250864D01*
Y259348D01*
X90600Y260998D01*
Y322919D01*
X71650Y341869D01*
Y362546D01*
X55189Y379007D01*
X49772D01*
X43170Y385609D01*
Y386901D01*
X23825Y406246D01*
Y559347D01*
X18960Y570999D01*
Y572061D01*
G01X510000Y173500D02*
Y166000D01*
X513500Y162500D01*
Y135000D01*
X521500Y127000D01*
Y118000D01*
X524000Y115500D01*
Y112759D01*
X523100Y111859D01*
Y91867D01*
X487186Y55953D01*
X469602D01*
X466659Y53010D01*
X441917D01*
X422646Y48040D01*
X422520Y47914D01*
X357220D01*
X355750Y46444D01*
X345966D01*
X345162Y47243D01*
X344702Y47699D01*
X344698Y47701D01*
X344576Y47821D01*
X316100Y58641D01*
X266970D01*
X260710Y64901D01*
X256870D01*
X253412Y68359D01*
X226367D01*
X219878Y70311D01*
X211220Y76423D01*
X160038D01*
X157880Y78577D01*
X151460D01*
X147270Y82767D01*
X139990Y93784D01*
Y107442D01*
X107740Y139692D01*
Y153462D01*
X94490Y166712D01*
Y207437D01*
X93622Y209885D01*
X89918Y220785D01*
X89663Y221041D01*
X89570Y221301D01*
X89250Y221453D01*
X85210Y225493D01*
Y237388D01*
X84754Y237844D01*
Y253212D01*
X87700Y256158D01*
Y259866D01*
X89080Y261246D01*
Y322671D01*
X70400Y341351D01*
Y362025D01*
X54668Y377757D01*
X49254D01*
X41920Y385091D01*
Y386260D01*
X22570Y405610D01*
Y559006D01*
X22155Y559421D01*
X17235Y570696D01*
Y577781D01*
X17876Y578422D01*
G01X116370Y785941D02*
X115800Y785371D01*
Y781633D01*
X62470Y728303D01*
Y673841D01*
X48000Y659371D01*
X39747D01*
X20156Y639780D01*
Y582405D01*
X25335Y577226D01*
Y554177D01*
X25197Y554039D01*
Y406817D01*
X44420Y387594D01*
Y386127D01*
X50290Y380257D01*
X55707D01*
X72900Y363064D01*
Y342395D01*
X94925Y320370D01*
Y263068D01*
X90487Y258630D01*
Y235020D01*
X90390Y234857D01*
X90487Y234471D01*
Y234340D01*
X92047Y228264D01*
X93660Y221851D01*
X93707Y221804D01*
X93711Y221788D01*
X97220Y218279D01*
Y168637D01*
X110450Y155407D01*
Y140528D01*
X141780Y109198D01*
X142490Y108487D01*
Y95067D01*
X156480Y81077D01*
X162500D01*
X164214Y79363D01*
X218994D01*
X227100Y71257D01*
X254278D01*
X258134Y67401D01*
X261750D01*
X267907Y61244D01*
X316719D01*
X316990Y61141D01*
X345719Y50222D01*
X347010Y48944D01*
X354290D01*
X355760Y50414D01*
X421830D01*
X422427Y50568D01*
X428295Y56436D01*
X464170D01*
G01X23610Y568111D02*
Y577050D01*
X18906Y581754D01*
Y640298D01*
X41190Y662582D01*
X49443D01*
X60500Y673639D01*
Y729545D01*
X97390Y766435D01*
G01X125960Y785699D02*
X125320Y785059D01*
Y780369D01*
X120460Y775509D01*
X116748D01*
X67710Y726471D01*
Y672009D01*
X49640Y653939D01*
X45110D01*
X42915Y651744D01*
Y649492D01*
X26460Y633037D01*
Y601559D01*
X27356Y600663D01*
Y593519D01*
X26387Y592550D01*
Y583589D01*
X31150Y578826D01*
Y553207D01*
X32397Y551960D01*
Y550530D01*
X31165Y549298D01*
Y475455D01*
X32600Y474020D01*
Y407897D01*
X49388Y391109D01*
X50160D01*
X53219Y388050D01*
X55001D01*
X78480Y364571D01*
Y362789D01*
X78487Y362782D01*
X78490D01*
Y361748D01*
X78480Y361738D01*
Y343899D01*
X110487Y311892D01*
Y217208D01*
X104685Y211406D01*
Y173560D01*
X114390Y163855D01*
Y140125D01*
X144400Y110115D01*
X144420Y110094D01*
X144990Y109522D01*
Y96103D01*
X157382Y83711D01*
X163570D01*
X165172Y82109D01*
X220812D01*
X228944Y73977D01*
X255394D01*
X259470Y69901D01*
X262790D01*
X266045Y66646D01*
X329545D01*
X341799Y54393D01*
X347114Y52374D01*
X347119Y52369D01*
X347425Y52065D01*
X348050Y51444D01*
X352690D01*
X352945Y51698D01*
X354164Y52914D01*
X421223D01*
X428855Y60546D01*
X471388D01*
X472313Y61471D01*
X482315D01*
X483240Y60546D01*
G01X475310Y59746D02*
X474300Y58736D01*
X428818D01*
X421773Y51691D01*
X421670Y51664D01*
X354793D01*
X353323Y50194D01*
X347530D01*
X346540Y51178D01*
X346422Y51295D01*
X340230Y53649D01*
X328483Y65396D01*
X265525D01*
X262270Y68651D01*
X258950D01*
X254928Y72673D01*
X227950D01*
X220010Y80613D01*
X164900D01*
X163052Y82461D01*
X156864D01*
X143740Y95585D01*
Y109005D01*
X143170Y109577D01*
X113060Y139687D01*
Y161523D01*
X110351Y164232D01*
X107033D01*
X104280Y166985D01*
Y170429D01*
X99724Y174985D01*
Y219839D01*
X98767Y220796D01*
Y223847D01*
X95209Y227405D01*
X92987Y235086D01*
Y256199D01*
X97425Y260637D01*
Y321418D01*
X75980Y342863D01*
Y363529D01*
X56752Y382757D01*
X51331D01*
X46925Y387163D01*
Y388634D01*
X29975Y405584D01*
Y472791D01*
X27697Y475069D01*
Y552485D01*
X27835Y552623D01*
Y578602D01*
X23887Y582550D01*
Y593586D01*
X24856Y594555D01*
Y597037D01*
X23960Y597933D01*
Y635423D01*
X39650Y651113D01*
Y652015D01*
X44074Y656439D01*
X48604D01*
X65210Y673045D01*
Y727507D01*
X118321Y780618D01*
X120090D01*
G01X475030Y63879D02*
X471031D01*
X469639Y62487D01*
X429020D01*
X421444Y54911D01*
X354390D01*
X352424Y52947D01*
X352170Y52694D01*
X348570D01*
X347973Y53285D01*
X347810Y53448D01*
X346007Y54134D01*
X345682Y54257D01*
X342500Y55467D01*
X330036Y67931D01*
X266537D01*
X263317Y71151D01*
X259990D01*
X255914Y75227D01*
X229667D01*
X221400Y83494D01*
X165557D01*
X164090Y84961D01*
X158451D01*
X146240Y97172D01*
Y111650D01*
X145670Y112222D01*
X145650Y112243D01*
X130820Y127073D01*
X115830Y142064D01*
Y170517D01*
X107185Y179162D01*
Y207248D01*
X112987Y213050D01*
Y312934D01*
X81180Y344741D01*
Y365637D01*
X62280Y384537D01*
Y386632D01*
X54055Y394857D01*
X52381D01*
X51560Y394036D01*
X50125D01*
X35965Y408196D01*
Y542171D01*
X35832Y542304D01*
Y544774D01*
X36206Y545148D01*
Y577317D01*
X31415Y582108D01*
Y616129D01*
X32469Y617183D01*
Y633187D01*
X70230Y670948D01*
Y724080D01*
X119159Y773009D01*
X125363D01*
X129710Y777356D01*
Y781316D01*
X130850Y782456D01*
G01X111220Y160923D02*
X106850D01*
X105640Y162132D01*
X98470Y169302D01*
Y218813D01*
X94792Y222491D01*
X91737Y234659D01*
Y257106D01*
X96175Y261544D01*
Y320891D01*
X74510Y342556D01*
Y363228D01*
X56231Y381507D01*
X50810D01*
X45672Y386645D01*
X45670D01*
Y388115D01*
X45022Y388763D01*
X45020D01*
X26447Y407336D01*
Y553521D01*
X26585Y553659D01*
Y577747D01*
X22637Y581695D01*
Y594104D01*
X23606Y595073D01*
Y596511D01*
X22710Y597407D01*
Y640566D01*
X40265Y658121D01*
X48518D01*
X63870Y673473D01*
Y727935D01*
X118169Y782234D01*
Y783857D01*
G01X127290Y781982D02*
Y776704D01*
X124845Y774259D01*
X117266D01*
X68960Y725953D01*
Y671489D01*
X29019Y631548D01*
Y613694D01*
X30000Y612713D01*
Y581755D01*
X34956Y576799D01*
Y551318D01*
X32415Y548777D01*
Y475996D01*
X33850Y474561D01*
Y408415D01*
X49906Y392359D01*
X50850D01*
X53909Y389300D01*
X55522D01*
X79830Y364992D01*
Y344323D01*
X80280Y343873D01*
Y343870D01*
X111737Y312413D01*
Y213568D01*
X105935Y207766D01*
Y176195D01*
X106760Y175370D01*
G01X106090Y167615D02*
Y170387D01*
X103435Y173042D01*
Y218049D01*
X104560Y219174D01*
Y228102D01*
X100590Y232072D01*
Y236823D01*
X94237Y243176D01*
Y255235D01*
X98675Y259673D01*
Y321936D01*
X77230Y343381D01*
Y364050D01*
X54480Y386800D01*
X52700D01*
X49641Y389859D01*
X48870D01*
X31340Y407389D01*
Y473204D01*
X28947Y475597D01*
Y551967D01*
X29085Y552105D01*
Y579120D01*
X25137Y583068D01*
Y593068D01*
X26106Y594037D01*
Y597555D01*
X25210Y598451D01*
Y633555D01*
X41660Y650005D01*
Y652257D01*
X44592Y655189D01*
X49122D01*
X66460Y672527D01*
Y726989D01*
X117374Y777903D01*
X121086D01*
X122720Y779537D01*
Y785051D01*
G01X108910Y193194D02*
Y206671D01*
X114237Y211998D01*
Y313729D01*
X82430Y345536D01*
Y366358D01*
X63720Y385068D01*
Y386960D01*
X47762Y402918D01*
X45573D01*
X37635Y410856D01*
Y448109D01*
X39715Y450189D01*
Y530413D01*
X37215Y532913D01*
Y542689D01*
X37082Y542822D01*
Y544254D01*
X40074Y547246D01*
Y575833D01*
X32715Y583192D01*
Y598488D01*
X34865Y600638D01*
Y602952D01*
X33955Y603862D01*
Y632821D01*
X51438Y650304D01*
X54466D01*
X55480Y651318D01*
Y654430D01*
X71480Y670430D01*
Y723562D01*
X119677Y771759D01*
X126841D01*
X132575Y777493D01*
Y783686D01*
X130660Y785601D01*
G01X479450Y63721D02*
X477468Y65703D01*
X470415D01*
X468449Y63737D01*
X427953D01*
X420505Y56289D01*
X353994D01*
X351649Y53944D01*
X349090D01*
X348510Y54520D01*
X345410Y55700D01*
X344353Y56102D01*
X330900Y69554D01*
X267050D01*
X264203Y72401D01*
X260510D01*
X256434Y76477D01*
X230199D01*
X221664Y85012D01*
X166520D01*
X165309Y86223D01*
X159832D01*
X157408Y88647D01*
Y100474D01*
X151580Y106302D01*
X148670Y109215D01*
Y110992D01*
X132075Y127587D01*
Y131115D01*
X131065Y132125D01*
X129952D01*
X117220Y144857D01*
Y172327D01*
X110805Y178742D01*
Y206730D01*
X115487Y211412D01*
Y314247D01*
X83680Y346054D01*
Y367082D01*
X65430Y385332D01*
Y387018D01*
X47030Y405418D01*
X44841D01*
X38885Y411374D01*
Y447104D01*
X40965Y449184D01*
Y531706D01*
X43682Y534423D01*
Y544044D01*
X41324Y546402D01*
Y576351D01*
X36165Y581510D01*
Y607477D01*
X35205Y608437D01*
Y613955D01*
X38010Y616760D01*
Y635108D01*
X51956Y649054D01*
X54984D01*
X56730Y650800D01*
Y653912D01*
X72730Y669912D01*
Y722685D01*
X120115Y770070D01*
X126920D01*
X134464Y777614D01*
Y780691D01*
X135470Y781697D01*
G01X135610Y784521D02*
X137440Y782691D01*
Y778037D01*
X128223Y768820D01*
X120633D01*
X74140Y722327D01*
Y669554D01*
X58448Y653862D01*
Y650750D01*
X53351Y645653D01*
X50323D01*
X39640Y634970D01*
Y607318D01*
X37635Y605313D01*
Y581811D01*
X43330Y576116D01*
Y563513D01*
X45192Y561651D01*
Y545100D01*
X47865Y542427D01*
Y536830D01*
X42215Y531180D01*
Y448665D01*
X40135Y446585D01*
Y411892D01*
X45359Y406668D01*
X47548D01*
X66680Y387536D01*
Y385850D01*
X84930Y367600D01*
Y346572D01*
X116737Y314765D01*
Y210423D01*
X112530Y206216D01*
Y186363D01*
G01X139600Y781281D02*
Y778429D01*
X128052Y766881D01*
X124330D01*
X75390Y717941D01*
Y664961D01*
X51382Y640953D01*
X48303D01*
X41225Y633875D01*
Y591814D01*
X44580Y588459D01*
Y564904D01*
X46450Y563034D01*
Y545610D01*
X49115Y542945D01*
Y535753D01*
X43465Y530103D01*
Y446828D01*
X41385Y444748D01*
Y412410D01*
X45877Y407918D01*
X48066D01*
X67930Y388054D01*
Y386817D01*
X86180Y368567D01*
Y347090D01*
X117987Y315283D01*
Y186249D01*
X113195Y181457D01*
Y178125D01*
X119340Y171980D01*
Y147623D01*
X133330Y133633D01*
Y128108D01*
X149920Y111518D01*
Y109733D01*
X152100Y107552D01*
X158960Y100692D01*
Y95461D01*
X168069Y86352D01*
X222182D01*
X230641Y77893D01*
X256786D01*
X261028Y73651D01*
X264722D01*
X267569Y70804D01*
X332220D01*
X346339Y56685D01*
X348212Y55973D01*
X351900D01*
X353466Y57539D01*
X414832D01*
X422280Y64987D01*
X453746D01*
X456868Y68109D01*
X479486D01*
X486810Y60785D01*
G01X114920Y179082D02*
X119237Y183399D01*
Y315801D01*
X87430Y347608D01*
Y369085D01*
X69180Y387335D01*
Y388572D01*
X47004Y410748D01*
X44815D01*
X42635Y412928D01*
Y443493D01*
X44715Y445573D01*
Y529140D01*
X50365Y534790D01*
Y543468D01*
X47700Y546133D01*
Y564426D01*
X45832Y566294D01*
Y592959D01*
X46232Y593359D01*
Y611645D01*
X43055Y614822D01*
Y633937D01*
X48821Y639703D01*
X51900D01*
X76640Y664443D01*
Y717423D01*
X124848Y765631D01*
X129242D01*
X141325Y777714D01*
Y782951D01*
X139680Y784596D01*
G01X160480Y777583D02*
Y776770D01*
X126013Y742303D01*
Y741891D01*
X123245Y739123D01*
Y719708D01*
X123784Y719169D01*
Y688941D01*
X65567Y630724D01*
Y597942D01*
X53370Y585745D01*
Y574502D01*
X50870Y572002D01*
Y564008D01*
G01X119900Y754021D02*
X118542D01*
X110697Y746176D01*
Y711217D01*
X114434Y707480D01*
Y693372D01*
X62182Y641120D01*
X56840D01*
X50890Y635170D01*
X49450D01*
X49331Y635289D01*
X46175D01*
X44305Y633419D01*
Y615347D01*
X49282Y610370D01*
Y580107D01*
X49680Y579709D01*
G01X49620Y574212D02*
X51405Y575997D01*
Y610483D01*
X45755Y616133D01*
Y627769D01*
X49524Y631538D01*
X50969D01*
X58051Y638620D01*
X63218D01*
X116934Y692336D01*
Y710884D01*
X113197Y714621D01*
Y745140D01*
X119283Y751226D01*
X124444D01*
X151200Y777982D01*
Y782468D01*
X149810Y783858D01*
G01X155170Y780656D02*
Y778133D01*
X124977Y747940D01*
X119816D01*
X115897Y744021D01*
Y735219D01*
X119090Y732026D01*
Y717139D01*
X119634Y716595D01*
Y691217D01*
X63855Y635438D01*
X58913D01*
X51473Y627998D01*
X50475D01*
X50270Y627793D01*
G01X48540Y624953D02*
Y628503D01*
X50125Y630088D01*
X51790D01*
X58390Y636688D01*
X63337D01*
X118384Y691735D01*
Y713250D01*
X117840Y713794D01*
Y731505D01*
X114647Y734698D01*
Y744539D01*
X119884Y749776D01*
X125045D01*
X152820Y777551D01*
Y782999D01*
X153320Y783499D01*
G01X149450Y780429D02*
Y778363D01*
X123363Y752276D01*
X118848D01*
X112147Y745575D01*
Y713221D01*
X115884Y709484D01*
Y692771D01*
X62783Y639670D01*
X57607D01*
X51501Y633564D01*
X46890D01*
G01X53988Y568748D02*
Y573344D01*
X54626Y573982D01*
Y585233D01*
X57532Y588139D01*
X62110D01*
X86090Y612119D01*
Y649479D01*
X125034Y688423D01*
Y719690D01*
X124495Y720229D01*
Y738416D01*
X130830Y744751D01*
Y744757D01*
X131560Y745487D01*
Y745488D01*
X135984D01*
X137290Y746794D01*
Y751140D01*
X163138Y776988D01*
Y778565D01*
G01X57710Y572918D02*
X90240Y605448D01*
Y646377D01*
X128097Y684234D01*
X129546D01*
X131332Y686020D01*
Y694008D01*
X130713Y694627D01*
Y705451D01*
X130845Y705583D01*
Y722926D01*
X130205Y723566D01*
Y735108D01*
X131905Y736808D01*
X137825D01*
X142624Y741607D01*
Y747846D01*
X172600Y777822D01*
Y780150D01*
G01X57070Y580074D02*
X57864D01*
X88790Y611000D01*
Y648358D01*
X129180Y688748D01*
Y719413D01*
X129395Y719628D01*
Y722270D01*
X128755Y722910D01*
Y736867D01*
X132359Y740471D01*
X135960D01*
X140870Y745381D01*
Y750901D01*
X167350Y777381D01*
Y778074D01*
G01X57440Y585607D02*
X61346D01*
X87340Y611601D01*
Y648961D01*
X127730Y689351D01*
Y720014D01*
X127945Y720229D01*
Y721669D01*
X127305Y722309D01*
Y739012D01*
X132400Y744107D01*
X136371D01*
X139010Y746746D01*
Y751092D01*
X165143Y777225D01*
Y779297D01*
X164630Y779810D01*
Y781222D01*
G01X59390Y642906D02*
Y645137D01*
X78150Y663897D01*
Y717165D01*
X125166Y764181D01*
X129560D01*
X142933Y777554D01*
Y783043D01*
X145473Y785583D01*
X159557D01*
X160320Y786346D01*
G01X56240Y630081D02*
Y630854D01*
X59574Y634188D01*
X64373D01*
X120884Y690699D01*
Y717116D01*
X120340Y717660D01*
Y732547D01*
X117147Y735740D01*
Y743503D01*
X119006Y745362D01*
X124167D01*
X156980Y778175D01*
Y781482D01*
X158622Y783124D01*
X161929D01*
X164103Y785298D01*
X169178D01*
X169350Y785470D01*
G01X169860Y782086D02*
X168999Y782947D01*
X163915D01*
X162434Y781466D01*
X159677D01*
X158580Y780369D01*
Y777612D01*
X124880Y743912D01*
X119607D01*
X118597Y742902D01*
Y737623D01*
X121790Y734430D01*
Y719110D01*
X122334Y718566D01*
Y690098D01*
X64973Y632737D01*
X60563D01*
X59530Y631704D01*
G01X125600Y759000D02*
X121753D01*
X81122Y718369D01*
Y693250D01*
X82355Y692017D01*
Y663222D01*
X63224Y644091D01*
X62160D01*
G01X89810Y765905D02*
X71160D01*
X66880Y761625D01*
G01X104300Y773100D02*
Y773185D01*
X91675Y785810D01*
X60357D01*
X56500Y789667D01*
G01X719800Y24920D02*
Y9107D01*
X715916Y5223D01*
X85996D01*
X73740Y17479D01*
Y20708D01*
G01X98700Y234650D02*
Y231911D01*
X103070Y227541D01*
Y220968D01*
X101449Y219347D01*
Y194368D01*
G01X162940Y406188D02*
X159838Y409290D01*
Y437535D01*
X159957Y437654D01*
Y469892D01*
X142090Y487759D01*
Y527154D01*
X127065Y542179D01*
Y558810D01*
X124565Y561310D01*
Y676899D01*
X132640Y684974D01*
X137407D01*
X139158Y686725D01*
G01X130260Y679836D02*
Y671043D01*
X126515Y667298D01*
Y565058D01*
X129020Y562553D01*
Y543276D01*
X144040Y528256D01*
Y488569D01*
X163852Y468757D01*
Y408037D01*
X164890Y406999D01*
Y388224D01*
X160710Y384044D01*
G01X175663Y386424D02*
X166850Y395237D01*
Y407898D01*
X165802Y408946D01*
Y470413D01*
X145990Y490225D01*
Y529067D01*
X131090Y543967D01*
Y564383D01*
X129065Y566408D01*
Y662250D01*
X135280Y668465D01*
Y679212D01*
G01X172760Y406540D02*
Y419031D01*
X168130Y423661D01*
Y471220D01*
X147940Y491410D01*
Y529877D01*
X137310Y540507D01*
Y560926D01*
X131865Y566371D01*
Y593695D01*
X132515Y594345D01*
Y599015D01*
X132190Y599340D01*
Y662616D01*
G01X130260Y679836D02*
X132581D01*
X133907Y681162D01*
X141318D01*
X144930Y677550D01*
Y668621D01*
X147165Y666386D01*
X186285D01*
X198169Y654502D01*
X242718D01*
X244482Y656266D01*
X266391D01*
X267140Y657015D01*
X274718D01*
X277658Y654075D01*
X285426D01*
X295710Y643790D01*
X297877D01*
X298887Y642780D01*
Y638401D01*
X301582Y635706D01*
X309209D01*
X310660Y637157D01*
X312100D01*
X313032Y636225D01*
X317171D01*
X321270Y632126D01*
X332070D01*
X336853Y627343D01*
X336860D01*
Y625729D01*
X336850Y625719D01*
Y602662D01*
X355209Y584303D01*
X442668D01*
X444011Y585646D01*
X453758D01*
X480672Y612560D01*
X505540D01*
X506440Y611660D01*
X515940D01*
X520130Y607470D01*
X552551D01*
X570610Y589411D01*
Y568844D01*
X577088Y562366D01*
Y559017D01*
X575038Y556967D01*
Y554725D01*
G01X134540Y267786D02*
X137094Y265232D01*
X177707D01*
X178929Y264010D01*
Y262244D01*
G01X575138Y559825D02*
Y561556D01*
X568660Y568034D01*
Y588603D01*
X554334Y602929D01*
X550885D01*
X550870Y602914D01*
X549434D01*
X546828Y605520D01*
X519320D01*
X518060Y606780D01*
X508533D01*
X506000Y609313D01*
Y609333D01*
X504723Y610610D01*
X481480D01*
X451826Y580956D01*
X351388D01*
X334900Y597444D01*
Y626536D01*
X331260Y630176D01*
X320456D01*
X317652Y632980D01*
X310330D01*
X308652Y631302D01*
X299673D01*
X285220Y645755D01*
Y648395D01*
X281490Y652125D01*
X276286D01*
X275445Y652966D01*
X268586D01*
X268066Y652446D01*
X265423D01*
X264269Y653600D01*
X246410D01*
X243604Y650794D01*
X221890D01*
X220629Y652055D01*
X197850D01*
X187814Y662091D01*
X174046D01*
X171702Y664435D01*
X146358D01*
X142840Y667953D01*
Y676882D01*
X140510Y679212D01*
X135280D01*
G01X205903Y101477D02*
X207108D01*
X208570Y102939D01*
Y130636D01*
X182800Y156406D01*
X174870D01*
X166708Y164568D01*
X161448D01*
X158800Y167216D01*
Y187761D01*
X194280Y223241D01*
Y226243D01*
X200621Y232584D01*
Y236472D01*
X201302Y237153D01*
Y241850D01*
X203369Y243917D01*
Y245064D01*
X213199Y254894D01*
X234167D01*
X237090Y257817D01*
Y264160D01*
X239569Y266639D01*
G01X162335Y512456D02*
X166530Y508648D01*
X178621Y496557D01*
X207937D01*
X213553Y498954D01*
X221070Y505525D01*
X221379Y505792D01*
X222753Y506997D01*
X229363Y513607D01*
X230199D01*
G01X231275D02*
X232043D01*
X233626Y515190D01*
G01X159196Y515612D02*
X161981D01*
X165032Y512561D01*
X167180Y510898D01*
X179471Y498607D01*
X207220D01*
X208680Y498882D01*
X212878Y500652D01*
X220281Y507025D01*
X228446Y515190D01*
X230476D01*
G01X159179Y521893D02*
X168688Y531402D01*
X168750D01*
X173378Y533105D01*
X179730D01*
X184665Y532275D01*
X187981D01*
X189390Y532900D01*
X190070Y533201D01*
X196015Y534656D01*
X223906D01*
X225475Y533087D01*
X232180Y529984D01*
X234077Y529685D01*
X235199Y528563D01*
Y528033D01*
G01Y527223D02*
Y525305D01*
G01Y524070D02*
Y521982D01*
G01Y520930D02*
Y519916D01*
X236776Y518339D01*
G01X162335Y521906D02*
Y521210D01*
X163087Y520458D01*
X164414D01*
X165212Y521256D01*
Y525431D01*
X167287Y527506D01*
X169181D01*
X170851Y525836D01*
X174953D01*
X175493Y526376D01*
X182932D01*
X183659Y527103D01*
X204316D01*
X205257Y528044D01*
Y528822D01*
G01X159180Y528227D02*
X165595Y533985D01*
Y534024D01*
X166333Y534219D01*
X173287Y534731D01*
X180454Y536076D01*
G01X182037D02*
X182246Y535867D01*
X185217D01*
X185516Y536166D01*
X186921D01*
X187287Y536026D01*
X189844D01*
X200307Y541678D01*
X210705D01*
X215354Y537029D01*
X222568D01*
X224207Y536155D01*
X227326Y533920D01*
X228609Y533242D01*
X232016Y531440D01*
X234039Y530980D01*
X237143Y529706D01*
X238251Y528598D01*
G01X238355Y527178D02*
Y525231D01*
G01Y523945D02*
X237309Y522318D01*
X236776Y521489D01*
G01X233626Y540386D02*
X232059Y542585D01*
Y543025D01*
G01Y543939D02*
Y544303D01*
X230724Y545638D01*
X217345Y554416D01*
X213307Y557066D01*
X199410Y564965D01*
X185220D01*
X184951Y564695D01*
X175030Y560219D01*
X171659Y557805D01*
X170597Y557045D01*
X167499Y555525D01*
X166254Y554749D01*
X165454Y553949D01*
X162336Y550253D01*
G01X154140Y577815D02*
Y591945D01*
X150380Y595705D01*
Y602885D01*
G01X165707Y506156D02*
X165745Y506104D01*
X177342Y494507D01*
X209790D01*
X217920Y498983D01*
X222850Y501698D01*
X225509Y504357D01*
Y506410D01*
X226423Y507324D01*
X227070D01*
G01X227587D02*
X228227D01*
X228908Y508005D01*
Y508543D01*
G01Y509528D02*
X230476Y512040D01*
G01X172087Y510536D02*
X172947Y508553D01*
X173345Y507634D01*
X180322Y500657D01*
X205020D01*
X210300Y504061D01*
X211739D01*
X219492Y509136D01*
X227111Y516755D01*
X230041D01*
G01X231401D02*
X233220D01*
G01X234055D02*
X234635D01*
X235192Y516198D01*
Y515507D01*
G01Y514472D02*
Y513587D01*
X233645Y512040D01*
X233626D01*
G01X168189Y514331D02*
X167933Y517761D01*
Y520363D01*
X169026Y521456D01*
X181146D01*
X183588Y521200D01*
X207464D01*
X208190Y521926D01*
X210760Y522853D01*
X219904D01*
G01X181231Y512455D02*
X179160Y510384D01*
Y509658D01*
X182006Y506812D01*
X189594D01*
X193175Y510393D01*
X194353D01*
X195071Y509675D01*
Y507561D01*
X195763Y506869D01*
X196777D01*
X197521Y507613D01*
Y509675D01*
X198239Y510393D01*
X199253D01*
X199971Y509675D01*
Y507561D01*
X200663Y506869D01*
X201677D01*
X202421Y507613D01*
Y509956D01*
X202858Y510393D01*
X203472D01*
X205003Y508862D01*
X205514D01*
X207030Y510378D01*
X209443D01*
X212874Y513809D01*
X215393D01*
X217609Y516025D01*
Y516353D01*
G01X224460Y519904D02*
X216367Y511811D01*
X213810D01*
X210274Y508275D01*
X207827D01*
X205950Y506398D01*
X204108D01*
X202529Y504819D01*
X181590D01*
X175298Y511111D01*
Y514280D01*
X175937Y514919D01*
X178213D01*
X178656Y514476D01*
Y513027D01*
X178085Y512456D01*
G01X173252Y515693D02*
Y513477D01*
X174199Y509642D01*
X174237D01*
X181172Y502707D01*
X203329D01*
X204864Y504242D01*
X206695D01*
X208634Y506181D01*
X211159D01*
X214889Y509911D01*
X217367D01*
X225795Y518339D01*
X230476D01*
G01Y521489D02*
X224142D01*
X221306Y518653D01*
X210717D01*
X208380Y516316D01*
Y514771D01*
X207702Y514093D01*
X202540D01*
X201422Y515211D01*
Y515938D01*
X200704Y516656D01*
X199690D01*
X198972Y515938D01*
Y515211D01*
X198254Y514493D01*
X197240D01*
X196522Y515211D01*
Y515938D01*
X195804Y516656D01*
X194790D01*
X194072Y515938D01*
Y515211D01*
X193354Y514493D01*
X191154D01*
X188850Y512189D01*
X185685D01*
X184758Y513116D01*
Y514991D01*
X182343Y517406D01*
X180077D01*
X179524Y516853D01*
X175990D01*
X174937Y517906D01*
X170925D01*
X169615Y519216D01*
G01X178986Y529770D02*
X179236Y530020D01*
X182542D01*
X183809Y528753D01*
X201895D01*
X204458Y531316D01*
X222746D01*
X227852Y526210D01*
X229813D01*
G01X231040D02*
X232055D01*
X233626Y524639D01*
G01X219328Y528823D02*
X219304D01*
X217200Y526719D01*
X206975D01*
X205309Y525053D01*
X176132D01*
X175435Y524356D01*
X170017D01*
X168617Y525756D01*
G01X230476Y524639D02*
X227423D01*
X222789Y529273D01*
X222150D01*
X220802Y527925D01*
Y526050D01*
X219803Y525051D01*
X208307D01*
X206106Y522850D01*
X192280D01*
X191727Y523403D01*
X188509D01*
X187956Y522850D01*
X183612D01*
X182609Y523853D01*
X176352D01*
X175216Y522717D01*
X167606D01*
X166837Y523486D01*
G01X223376Y523322D02*
X222877D01*
X220258Y520703D01*
X209867D01*
X207714Y518550D01*
X189445D01*
X188727Y517832D01*
Y517003D01*
X188277Y516553D01*
X185609D01*
X182989Y519173D01*
X180489D01*
X179309Y520353D01*
X176954D01*
X176384Y519783D01*
X172371D01*
G01X236776Y540386D02*
X235192Y538802D01*
X234078D01*
G01X233081D02*
X231326D01*
G01X230105D02*
X228060D01*
X226408Y540454D01*
X217124D01*
X213560Y544018D01*
Y544602D01*
X212384Y545778D01*
X209809D01*
X209359Y546228D01*
Y546672D01*
X208641Y547390D01*
X207627D01*
X206909Y546672D01*
Y546228D01*
X206459Y545778D01*
X194904D01*
X190964Y541838D01*
X180504D01*
X179044Y543298D01*
Y544386D01*
X180247Y545589D01*
X186624D01*
X186841Y545372D01*
G01X174930Y547106D02*
X170509Y542685D01*
Y541157D01*
X171970Y539696D01*
X191748D01*
X195780Y543728D01*
X211133D01*
X216057Y538804D01*
X224558D01*
X227700Y535662D01*
X230219D01*
G01X231361D02*
X233235D01*
G01X234319D02*
X235202D01*
X236776Y537236D01*
G01X173163Y551903D02*
Y552407D01*
X179258Y558502D01*
X186270Y561665D01*
X197556D01*
X207428Y556521D01*
X214081Y551252D01*
X215474Y549859D01*
X218751Y546583D01*
Y543835D01*
G01X230476Y540386D02*
X221379Y547587D01*
X215474Y552261D01*
X207995Y558182D01*
Y558183D01*
X198972Y563315D01*
X185910D01*
X175858Y558782D01*
X172844Y556620D01*
X171889Y555934D01*
X167105Y552882D01*
G01X683112Y487660D02*
X681373Y489399D01*
X678933D01*
X654940Y513392D01*
X654825Y513508D01*
Y523605D01*
X647230Y531200D01*
X632013D01*
X621706Y541507D01*
X614197D01*
X602712Y552992D01*
Y558673D01*
X603818Y559779D01*
Y568933D01*
X601780Y570971D01*
Y596367D01*
X598354Y599793D01*
Y613483D01*
X577308Y634529D01*
X562517D01*
X560931Y636115D01*
X556152D01*
X551440Y640827D01*
X533103D01*
X530070Y643860D01*
X512493D01*
X507223Y638590D01*
X496258D01*
X491365Y633697D01*
X475105D01*
X473915Y634887D01*
Y638646D01*
X472730Y639831D01*
Y650700D01*
X469525Y653905D01*
X468090D01*
X466967Y652782D01*
X454100D01*
X451318Y650000D01*
X443068D01*
X440000Y653068D01*
X433992D01*
X432603Y654457D01*
X421290D01*
X420375Y653542D01*
X412844D01*
X411073Y655313D01*
X398111D01*
X398101Y655303D01*
X394514D01*
X390527Y651316D01*
X384507D01*
X380655Y647464D01*
X378330D01*
X377913Y647881D01*
X371992D01*
X367561Y643450D01*
X360840D01*
X359230Y645060D01*
X343863D01*
X341905Y643102D01*
X336478D01*
X334345Y640969D01*
X331420D01*
X331160Y641229D01*
X329030D01*
X328750Y640949D01*
X324131D01*
X319391Y645689D01*
X301305D01*
X293810Y653184D01*
X291329D01*
X284098Y660415D01*
X264880D01*
X264131Y659666D01*
X236220D01*
X234564Y658010D01*
X200195D01*
X190700Y667505D01*
Y690320D01*
X188650Y692370D01*
Y700078D01*
X185839Y702889D01*
Y707821D01*
X177250Y716410D01*
Y718458D01*
X175463Y720245D01*
G01X177920Y739302D02*
Y728930D01*
X173738Y724748D01*
Y717841D01*
X181837Y709742D01*
Y703965D01*
X184268Y701534D01*
Y671886D01*
X199702Y656452D01*
X235066D01*
X236830Y658216D01*
X265581D01*
X266330Y658965D01*
X283294D01*
X296519Y645740D01*
X298690D01*
X301380Y643050D01*
Y638666D01*
X302390Y637656D01*
X305520D01*
X306971Y639107D01*
X312912D01*
X313844Y638175D01*
X317987D01*
X322086Y634076D01*
X333380D01*
X333523Y633933D01*
X350828D01*
X352583Y632178D01*
X354020D01*
X356637Y634795D01*
X371253D01*
X372400Y635942D01*
X379920D01*
X380174Y635688D01*
X385827D01*
X390778Y640639D01*
X404690D01*
X405586Y641535D01*
X420926D01*
X421690Y640771D01*
X424720D01*
X427478Y638013D01*
X444487D01*
X445800Y636700D01*
X454847D01*
X459395Y632152D01*
X469905D01*
X474502Y627555D01*
X487146D01*
X489620Y625081D01*
Y622560D01*
X490040Y622140D01*
G01X192298Y286183D02*
Y286191D01*
X194348Y288241D01*
X199158D01*
X201154Y290237D01*
Y291334D01*
X206319Y296499D01*
Y296863D01*
G01X233626Y502591D02*
X228388Y497353D01*
X222753D01*
X217501Y492101D01*
X195805D01*
X193500Y489796D01*
G01X181232Y515607D02*
X181855D01*
X183107Y514355D01*
Y512013D01*
X184613Y510507D01*
X190308D01*
X192244Y512443D01*
X208573D01*
X211609Y515479D01*
Y516553D01*
G01X191457Y531553D02*
X192607Y530403D01*
X196484D01*
X197174Y531093D01*
Y532375D01*
X197736Y532937D01*
X199129D01*
X199624Y532442D01*
Y531191D01*
X200012Y530803D01*
X201611D01*
X203814Y533006D01*
X223056D01*
X228274Y527788D01*
X230476D01*
G01X215946Y544202D02*
X216860Y545116D01*
Y545767D01*
X214556Y548071D01*
X213540D01*
X213125Y547656D01*
X212109D01*
X211392Y548373D01*
Y549389D01*
X211807Y549804D01*
Y550820D01*
X211206Y551421D01*
X207041Y554717D01*
X205402Y555568D01*
X204434Y555262D01*
X203727Y553907D01*
X202760Y553602D01*
X201859Y554072D01*
X201554Y555039D01*
X202261Y556395D01*
X201956Y557364D01*
X201055Y557834D01*
X200088Y557529D01*
X199420Y556246D01*
X198453Y555941D01*
X197552Y556411D01*
X197247Y557379D01*
X197915Y558661D01*
X197610Y559630D01*
X196871Y560015D01*
X191280D01*
X190549Y559284D01*
X189261D01*
X188530Y560015D01*
X186798D01*
X185745Y558962D01*
Y557948D01*
X186559Y557133D01*
Y556119D01*
X185840Y555400D01*
X184826D01*
X184012Y556215D01*
X182998D01*
X181234Y554451D01*
Y553406D01*
X181232Y553404D01*
Y553402D01*
G01X183566Y722353D02*
X190085Y715834D01*
Y706459D01*
X193793Y702751D01*
X195607D01*
X210600Y687758D01*
X224336D01*
G01X224060Y690317D02*
X218945D01*
X202756Y706506D01*
X199800D01*
X194419Y711887D01*
Y716500D01*
X188566Y722353D01*
G01X220580Y692876D02*
X218425D01*
X203715Y707586D01*
Y713082D01*
X194464Y722333D01*
X193566D01*
G01X310380Y473942D02*
Y523528D01*
X307415Y526493D01*
Y572832D01*
X299685Y580562D01*
X287100D01*
X285462Y582200D01*
X265324D01*
X263250Y584274D01*
X251357D01*
X250350Y585281D01*
X233100D01*
X231763Y586618D01*
X207750D01*
X203512Y582380D01*
X198175D01*
X197165Y583390D01*
Y585661D01*
X201339Y589835D01*
Y617340D01*
X199786Y618893D01*
G01X198890Y584105D02*
X202809Y588024D01*
X244778D01*
X245635Y588881D01*
X254297D01*
X256890Y586288D01*
X264832D01*
X266970Y584150D01*
X286272D01*
X288349Y582073D01*
X299659D01*
X309140Y572592D01*
Y529640D01*
X312560Y526220D01*
Y472336D01*
X308293Y468069D01*
X308010D01*
X307800Y467859D01*
G01X207178Y591595D02*
X207405Y591368D01*
X239692D01*
X239798Y591474D01*
X254472D01*
X256574Y589372D01*
X264508D01*
X267780Y586100D01*
X287473D01*
X289550Y584023D01*
X303198D01*
X311150Y576071D01*
Y530431D01*
X314630Y526951D01*
Y473478D01*
X315980Y472128D01*
G01X604820Y555040D02*
X605240Y555460D01*
Y556152D01*
X606162Y557074D01*
Y565388D01*
X605352Y566198D01*
Y571943D01*
X603561Y573734D01*
Y597955D01*
X599880Y601636D01*
Y614008D01*
X577908Y635980D01*
X564920D01*
X561259Y639641D01*
X554874D01*
X552238Y642277D01*
X533726D01*
X530693Y645310D01*
X511784D01*
X506514Y640040D01*
X495652D01*
X493166Y637554D01*
X478438D01*
X474180Y641812D01*
Y652964D01*
X469200Y657944D01*
X467667D01*
X466020Y656297D01*
X459402D01*
X457456Y654351D01*
X444920D01*
X439213Y660058D01*
X414198D01*
X412700Y658560D01*
X398898D01*
X397655Y659803D01*
X395436D01*
X389630Y653997D01*
X378930D01*
X376897Y651964D01*
X367155D01*
X365340Y650149D01*
Y650072D01*
X364055Y648787D01*
X362620D01*
X360476Y650931D01*
X349284D01*
X344905Y646552D01*
X339950D01*
X337950Y644552D01*
X335868D01*
X335773Y644457D01*
X322683D01*
X320001Y647139D01*
X301910D01*
X294414Y654634D01*
X291939D01*
X284708Y661865D01*
X264179D01*
X263430Y661116D01*
X235610D01*
X233969Y659475D01*
X203180D01*
X202920Y659735D01*
X200910D01*
G01X199510Y663158D02*
X200760Y661908D01*
X203241D01*
X204491Y663158D01*
X231204D01*
X234736Y666690D01*
X266270D01*
X269809Y670229D01*
X280493D01*
X286791Y663931D01*
X290340D01*
X294311Y659960D01*
X299470D01*
X303120Y656310D01*
Y652523D01*
X305360Y650283D01*
X322064D01*
X324990Y647357D01*
X330620D01*
X330931Y647668D01*
X336946D01*
X338730Y649452D01*
X342819D01*
X350402Y657035D01*
X357703D01*
X360930Y660262D01*
X362370D01*
X362842Y659790D01*
X368088D01*
X368636Y659242D01*
X376664D01*
X379386Y661964D01*
X384766D01*
X384840Y661890D01*
X390368D01*
X393182Y664704D01*
X399140D01*
X399158Y664686D01*
X410675D01*
X411917Y665928D01*
X418657D01*
X420650Y663935D01*
X439726D01*
X444555Y659107D01*
X445990D01*
X446134Y659251D01*
X464864D01*
X466457Y660844D01*
X470402D01*
X477677Y653569D01*
Y642417D01*
X479595Y640499D01*
X485467D01*
X487594Y642626D01*
X491820D01*
X494445Y645251D01*
X497090D01*
X499726Y647887D01*
X505010D01*
X505679Y648556D01*
X509390D01*
X509736Y648210D01*
X532222D01*
X535255Y645177D01*
X554074D01*
X556710Y642541D01*
X566867D01*
X569220Y640188D01*
X579078D01*
X608990Y610276D01*
Y581617D01*
X612546Y578061D01*
Y565779D01*
X610070Y563303D01*
Y557588D01*
G01X606300Y551844D02*
X607080Y552624D01*
Y555938D01*
X607768Y556626D01*
Y565166D01*
X608802Y566200D01*
Y567638D01*
X607301Y569139D01*
Y593041D01*
X607461Y593201D01*
Y609754D01*
X578477Y638738D01*
X568610D01*
X566257Y641091D01*
X556106D01*
X553470Y643727D01*
X534462D01*
X531429Y646760D01*
X509126D01*
X508780Y647106D01*
X507340D01*
X506671Y646437D01*
X500466D01*
X497830Y643801D01*
X495055D01*
X492430Y641176D01*
X489393D01*
X487266Y639049D01*
X478994D01*
X475630Y642413D01*
Y653565D01*
X469801Y659394D01*
X467061D01*
X465414Y657747D01*
X457249D01*
X455303Y655801D01*
X445525D01*
X439770Y661556D01*
X415273D01*
X413593Y663236D01*
X397878D01*
X397860Y663254D01*
X395763D01*
X388523Y656014D01*
X374355D01*
X371882Y653541D01*
X364165D01*
X362121Y655585D01*
X351013D01*
X343430Y648002D01*
X339340D01*
X337414Y646076D01*
X331399D01*
X331230Y645907D01*
X324380D01*
X321698Y648589D01*
X302514D01*
X295410Y655693D01*
Y656239D01*
X291466Y660183D01*
X288450D01*
X283026Y665601D01*
X275735D01*
X273449Y663315D01*
X262889D01*
X262610Y663036D01*
X235470D01*
X233634Y661200D01*
X205410D01*
G01X198566Y722353D02*
X207170Y713749D01*
Y708209D01*
X219943Y695436D01*
X223707D01*
G01X223741Y700554D02*
X212410Y711885D01*
Y715831D01*
X209820Y718421D01*
Y721541D01*
X209017Y722344D01*
G01X203611Y722303D02*
X208290Y717624D01*
Y712135D01*
X221340Y699085D01*
Y697995D01*
G01X222710Y713706D02*
X222584Y713580D01*
X216815D01*
X215730Y714665D01*
Y721946D01*
X215090Y722586D01*
Y723117D01*
X212109Y726098D01*
X198234D01*
X196079Y723943D01*
G01X420290Y733741D02*
X406778Y720229D01*
X400010D01*
X397871Y722368D01*
X383232D01*
X378900Y726700D01*
Y734173D01*
X378910D01*
Y735198D01*
X377485Y736623D01*
X369149D01*
X361620Y729094D01*
X359530D01*
X358198Y730426D01*
X228608D01*
X219130Y720948D01*
Y716905D01*
X217530Y715305D01*
G01X463020Y661023D02*
X464542D01*
X466055Y662536D01*
Y663966D01*
X465045Y664976D01*
X463610D01*
X463452Y664818D01*
X458018D01*
X457860Y664976D01*
X451272D01*
X445173Y671075D01*
X443743D01*
X442571Y669903D01*
X428337D01*
X427549Y670691D01*
X397091D01*
X395469Y669069D01*
X379757D01*
X375482Y664794D01*
X364279D01*
X362888Y663403D01*
X361450D01*
X359678Y665175D01*
X351015D01*
X348050Y662210D01*
Y660073D01*
X341345Y653368D01*
X338295D01*
X335810Y650883D01*
X329496D01*
X328870Y650257D01*
X326210D01*
X319664Y656803D01*
X316353D01*
X312166Y660990D01*
X306021D01*
X305579Y661431D01*
X304560Y662450D01*
Y663056D01*
X300950Y666666D01*
X293077D01*
X276425Y683318D01*
X273506D01*
X267895Y688929D01*
Y695541D01*
X266885Y696551D01*
X263944D01*
X242614Y717881D01*
X224059D01*
X221320Y720620D01*
Y720698D01*
G01X464330Y663251D02*
X460441D01*
X458716Y661526D01*
X447016D01*
X445922Y662620D01*
X443740D01*
X440975Y665385D01*
X432855D01*
X430855Y667385D01*
X429420D01*
X428194Y666159D01*
X425385D01*
X422303Y669241D01*
X397827D01*
X394741Y666155D01*
X392575D01*
X389760Y663340D01*
X385450D01*
X385376Y663414D01*
X378780D01*
X376058Y660692D01*
X369246D01*
X368698Y661240D01*
X363444D01*
X362972Y661712D01*
X351675D01*
X349990Y660027D01*
Y659962D01*
X341946Y651918D01*
X339145D01*
X336345Y649118D01*
X330320D01*
X330009Y648807D01*
X325600D01*
X319054Y655353D01*
X315750D01*
X313672Y657431D01*
X305579D01*
X304500Y658510D01*
Y660316D01*
X302600Y662216D01*
X298776D01*
X296605Y664387D01*
X293263D01*
X290080Y667570D01*
X288650D01*
X288468Y667388D01*
X285392D01*
X278817Y673963D01*
X279128D01*
X263320Y689771D01*
Y695108D01*
X248096Y710332D01*
X218012D01*
X214280Y714064D01*
Y718094D01*
X213310Y719064D01*
G01X346750Y466532D02*
X345662D01*
X341220Y462090D01*
Y453565D01*
X339270Y451615D01*
Y445274D01*
X332798Y438802D01*
X320530D01*
X317628Y441704D01*
X312598D01*
X304220Y433326D01*
Y413590D01*
X288621Y397991D01*
X283100D01*
X282588Y397479D01*
X261140D01*
X252159Y388498D01*
X240955D01*
X240560Y388103D01*
X236793D01*
X236412Y387722D01*
G01X339506Y482841D02*
X338283D01*
X336210Y480768D01*
Y465117D01*
X334363Y456151D01*
Y453793D01*
X335970Y452186D01*
Y446645D01*
X331427Y442102D01*
X321913D01*
X319011Y445004D01*
X311230D01*
X300920Y434694D01*
Y416631D01*
X289457Y405168D01*
X273698D01*
X262912Y403025D01*
X260666Y400779D01*
X259280D01*
X256361Y397860D01*
X237390D01*
X231223Y391693D01*
Y391424D01*
G01X348220Y486484D02*
X347144Y485408D01*
X338420D01*
X334470Y481458D01*
Y465638D01*
X332710Y459620D01*
Y453109D01*
X334320Y451499D01*
Y447335D01*
X330737Y443752D01*
X322606D01*
X319704Y446654D01*
X310523D01*
X299270Y435401D01*
Y417647D01*
X288441Y406818D01*
X272484D01*
X262119Y404572D01*
X259976Y402429D01*
X258590D01*
X255708Y399547D01*
X236604D01*
X232240Y398228D01*
X230659Y396647D01*
X228798Y392715D01*
Y389972D01*
X228903Y389643D01*
X231457Y387089D01*
X232887D01*
X233900Y388102D01*
Y388640D01*
X235788Y390528D01*
X239546D01*
G01X236430Y393470D02*
X236967D01*
X239383Y395886D01*
X256722D01*
X259965Y399129D01*
X281898D01*
X282410Y399641D01*
X287937D01*
X302570Y414274D01*
Y434010D01*
X311914Y443354D01*
X318320D01*
X321222Y440452D01*
X332114D01*
X337620Y445958D01*
Y452635D01*
X338760Y453775D01*
Y474196D01*
X338762D01*
Y479636D01*
G01X421128Y292601D02*
X418997D01*
X416467Y295131D01*
X410378D01*
X406418Y291171D01*
Y290100D01*
X404359Y288041D01*
X396796D01*
X393960Y290877D01*
Y297323D01*
X392177Y299106D01*
X382121D01*
X376605Y293590D01*
X371886D01*
X364048Y285752D01*
X349635D01*
X346304Y282421D01*
X336995D01*
X330830Y288586D01*
Y288590D01*
X322473Y296944D01*
X306633D01*
X304921Y298656D01*
X296031D01*
X294200Y300487D01*
X272810D01*
X270399Y298076D01*
X257835D01*
X256755Y296996D01*
Y295310D01*
X257780Y294285D01*
X262469D01*
X262904Y293850D01*
G01X264600Y723086D02*
X261453Y719939D01*
X253462D01*
X248770Y724631D01*
G01X284020Y724956D02*
Y724962D01*
X282120Y726862D01*
X262451D01*
X258570Y722981D01*
G01X399598Y260251D02*
X398872D01*
X396870Y258249D01*
Y257178D01*
X391340Y251648D01*
X369208D01*
X368490Y250930D01*
Y249916D01*
X369208Y249198D01*
X384612D01*
X385330Y248480D01*
Y247466D01*
X384612Y246748D01*
X366014D01*
X357585Y238319D01*
X351384D01*
X316144Y273559D01*
X294075D01*
X284017Y283617D01*
X281840D01*
X281558Y283335D01*
X272612D01*
X270386Y281109D01*
Y280407D01*
G01X267386D02*
Y280995D01*
X270858Y284467D01*
X284370D01*
X291597Y277242D01*
X296796D01*
X298681Y275357D01*
X316691D01*
X336672Y255376D01*
X357686D01*
X359760Y253302D01*
X390549D01*
X395020Y257773D01*
Y259861D01*
X394380Y260501D01*
X394378D01*
G01X265825Y293987D02*
Y291708D01*
X268037Y289496D01*
X269602D01*
X271602Y291496D01*
X274486D01*
X278820Y295830D01*
X290314D01*
X292473Y293671D01*
X302408D01*
X305750Y290329D01*
X307552D01*
X308097Y289784D01*
X319701D01*
X333788Y275700D01*
X349438D01*
X352872Y279134D01*
X367316D01*
X375063Y286881D01*
X386620D01*
X388970Y284531D01*
Y281640D01*
X391758Y278852D01*
X397839D01*
X401328Y282341D01*
X404398D01*
X405298Y281441D01*
Y277541D01*
X406028Y276811D01*
X412154D01*
X413022Y275943D01*
Y270739D01*
X413740Y270021D01*
X414754D01*
X415472Y270739D01*
Y275943D01*
X416726Y277197D01*
X419784D01*
X421728Y279141D01*
G01X418588Y286681D02*
Y286678D01*
X417948Y286038D01*
X416790D01*
X416190Y286638D01*
Y292510D01*
X415472Y293228D01*
X414458D01*
X413740Y292510D01*
Y287696D01*
X413022Y286978D01*
X412008D01*
X411290Y287696D01*
Y290409D01*
X410562Y291137D01*
Y291141D01*
X409548D01*
X408840Y290433D01*
Y287079D01*
X408122Y286361D01*
X396052D01*
X392310Y290103D01*
Y294650D01*
X389719Y297241D01*
X382597D01*
X377292Y291936D01*
X372576D01*
X364740Y284100D01*
X350801D01*
X347361Y280660D01*
X336320D01*
X321752Y295228D01*
X306896D01*
X304608Y297516D01*
X295206D01*
X293314Y299408D01*
X272934D01*
X269642Y296116D01*
Y294717D01*
X268867Y293942D01*
G01X399608Y275211D02*
X398398Y276421D01*
X396941D01*
X395098Y274578D01*
Y271004D01*
X394065Y269971D01*
X390898D01*
X389780Y271089D01*
Y273082D01*
X388846Y274016D01*
X387808D01*
X387090Y274734D01*
Y276919D01*
X386372Y277637D01*
X385358D01*
X384640Y276919D01*
Y274734D01*
X383922Y274016D01*
X382908D01*
X382190Y274734D01*
Y277506D01*
X381472Y278224D01*
X380458D01*
X379740Y277506D01*
Y274734D01*
X379022Y274016D01*
X378008D01*
X377290Y274734D01*
Y277594D01*
X376572Y278312D01*
X375558D01*
X374840Y277594D01*
Y274734D01*
X374122Y274016D01*
X365244D01*
X360347Y269119D01*
X356764D01*
X356046Y269837D01*
Y270851D01*
X356764Y271569D01*
X357972D01*
X358690Y272287D01*
Y273301D01*
X357972Y274019D01*
X354314D01*
X353596Y273301D01*
Y269837D01*
X352878Y269119D01*
X350601D01*
X349883Y269837D01*
Y271256D01*
X349165Y271974D01*
X348151D01*
X347433Y271256D01*
Y269837D01*
X346715Y269119D01*
X345701D01*
X344983Y269837D01*
Y271256D01*
X344265Y271974D01*
X343251D01*
X342533Y271256D01*
Y269837D01*
X341815Y269119D01*
X340801D01*
X340083Y269837D01*
Y271256D01*
X339365Y271974D01*
X338351D01*
X337633Y271256D01*
Y269837D01*
X336915Y269119D01*
X335597D01*
X320160Y284556D01*
X313112D01*
X313105Y284563D01*
X310011D01*
X306022Y288552D01*
X292852D01*
X287796Y293608D01*
X279818D01*
X274162Y287952D01*
X272395D01*
X270626Y286183D01*
X270444D01*
G01X393458Y282931D02*
X393450Y282939D01*
Y284731D01*
X388453Y289727D01*
Y290743D01*
X390653Y292943D01*
Y293957D01*
X389934Y294675D01*
X388919D01*
X387700Y293456D01*
X386595D01*
X385877Y294174D01*
Y294866D01*
X385159Y295584D01*
X384145D01*
X383427Y294866D01*
Y294174D01*
X382709Y293456D01*
X381155D01*
X377981Y290282D01*
X373262D01*
X365425Y282445D01*
X351489D01*
X348051Y279007D01*
X335353D01*
X320897Y293463D01*
X307288D01*
X304312Y296439D01*
X294687D01*
X292569Y298558D01*
X273287D01*
X270492Y295763D01*
Y292110D01*
X269468Y291086D01*
X268943D01*
G01X265768Y287546D02*
X267131Y286183D01*
X268145D01*
X269770Y287808D01*
X270711D01*
X272371Y289468D01*
X274033D01*
X279207Y294642D01*
X288560D01*
X293139Y290063D01*
X303920D01*
X304553Y289430D01*
X307248D01*
X309722Y286956D01*
X315538D01*
X316664Y288082D01*
X317952D01*
X317999Y288035D01*
X319015D01*
X333008Y274042D01*
X350124D01*
X351755Y275673D01*
X352995D01*
X353713Y276391D01*
Y276714D01*
X354431Y277432D01*
X355445D01*
X356163Y276714D01*
Y276391D01*
X356881Y275673D01*
X357895D01*
X358613Y276391D01*
Y276714D01*
X359331Y277432D01*
X360345D01*
X361063Y276714D01*
Y276391D01*
X361781Y275673D01*
X362795D01*
X363513Y276391D01*
Y276714D01*
X364231Y277432D01*
X365245D01*
X365963Y276714D01*
Y276391D01*
X366681Y275673D01*
X370580D01*
X371505Y276598D01*
Y277614D01*
X370479Y278640D01*
Y279656D01*
X371196Y280373D01*
X372212D01*
X373238Y279347D01*
X374254D01*
X374878Y279971D01*
X375962D01*
X376680Y280689D01*
Y284153D01*
X377398Y284871D01*
X385663D01*
X386381Y284153D01*
Y283139D01*
X385663Y282421D01*
X379848D01*
X379130Y281703D01*
Y280689D01*
X379848Y279971D01*
X386381D01*
X390771Y275581D01*
X392508D01*
G01X273444Y286183D02*
X273728D01*
X280108Y292563D01*
X287506D01*
X293091Y286978D01*
Y286338D01*
X294381Y285048D01*
X297675D01*
X297869Y285242D01*
X304637D01*
X307552Y282327D01*
X320049D01*
X334911Y267465D01*
X363617D01*
X364335Y268183D01*
Y270490D01*
X366210Y272365D01*
X386842D01*
X387560Y271647D01*
Y270633D01*
X386842Y269915D01*
X367503D01*
X366785Y269197D01*
Y268183D01*
X367503Y267465D01*
X388850D01*
X389536Y268151D01*
X395475D01*
X396748Y269424D01*
Y270774D01*
X398755Y272781D01*
X401578D01*
X402218Y273421D01*
Y274311D01*
X403068Y275161D01*
X409948D01*
X410918Y274191D01*
Y267551D01*
X410348Y266981D01*
X408128D01*
X407748Y267361D01*
Y269851D01*
X407548Y270051D01*
X403288D01*
X403148Y270191D01*
G01X273618Y295387D02*
Y295958D01*
X275101Y297441D01*
X277181D01*
X277492Y297130D01*
X291398D01*
X293359Y295169D01*
X303126D01*
X306586Y291709D01*
X320122D01*
X334479Y277352D01*
X348745D01*
X352179Y280786D01*
X366105D01*
X373853Y288534D01*
X380418D01*
X381136Y289252D01*
Y291022D01*
X381854Y291740D01*
X382868D01*
X383586Y291022D01*
Y289252D01*
X384304Y288534D01*
X387301D01*
X390790Y285045D01*
Y282160D01*
X392448Y280502D01*
X397149D01*
X398528Y281881D01*
Y283378D01*
X399861Y284711D01*
X406508D01*
X406956Y284263D01*
Y279239D01*
X407674Y278521D01*
X408688D01*
X409406Y279239D01*
Y284713D01*
X410124Y285431D01*
X411138D01*
X411856Y284713D01*
Y279239D01*
X412574Y278521D01*
X413588D01*
X414306Y279239D01*
Y282842D01*
X415243Y283779D01*
X422358D01*
X423178Y284599D01*
Y284601D01*
G01X268944Y309643D02*
Y310912D01*
X268893Y310963D01*
Y312311D01*
X269844Y313262D01*
X271587D01*
X272106Y313781D01*
X294885D01*
X295740Y312926D01*
X308839D01*
X310052Y311713D01*
X324615D01*
X326344Y313442D01*
X331401D01*
X333540Y315581D01*
G01X265944Y309640D02*
Y308544D01*
X267705Y306783D01*
X278599D01*
X279880Y305502D01*
X282812D01*
X285572Y302742D01*
X298621D01*
X300201Y301162D01*
Y300874D01*
G01X324940Y413899D02*
X329057Y409782D01*
Y367581D01*
X325663Y364187D01*
X316532D01*
X307410Y355065D01*
Y354339D01*
X286078Y333007D01*
X284879D01*
X282743Y330871D01*
X277880D01*
X275121Y328112D01*
X264644D01*
X263690Y327158D01*
Y326484D01*
X262700Y325494D01*
G01X269456Y355353D02*
X280327D01*
X280851Y354829D01*
X305228D01*
X316128Y365729D01*
X325718D01*
X328007Y368018D01*
Y407683D01*
X321315Y414375D01*
Y420595D01*
X311610Y430300D01*
Y432528D01*
G01X345270Y452745D02*
X340920Y448395D01*
Y441824D01*
X336248Y437152D01*
X319837D01*
X316935Y440054D01*
X313282D01*
X305870Y432642D01*
Y411674D01*
X288737Y394541D01*
X283100D01*
X281856Y395785D01*
X262310D01*
X261061Y394536D01*
Y388233D01*
X261539Y387755D01*
G01X269410Y706003D02*
X268545Y705138D01*
X259170D01*
G01X426335Y267062D02*
Y266828D01*
X423288Y263781D01*
Y260321D01*
X421868Y258901D01*
X419848D01*
X419808Y258941D01*
X419738D01*
X419568Y259111D01*
X417744D01*
X413805Y255172D01*
Y245227D01*
X413087Y244509D01*
X412073D01*
X411355Y245227D01*
Y254946D01*
X410621Y255680D01*
X409582D01*
X408848Y254946D01*
Y243322D01*
X396831Y231305D01*
X386810D01*
X386092Y232023D01*
Y232406D01*
X385374Y233124D01*
X384360D01*
X383642Y232406D01*
Y232023D01*
X382924Y231305D01*
X381910D01*
X381192Y232023D01*
Y232406D01*
X380474Y233124D01*
X379460D01*
X378742Y232406D01*
Y232023D01*
X378024Y231305D01*
X377010D01*
X376292Y232023D01*
Y232406D01*
X375574Y233124D01*
X374560D01*
X373842Y232406D01*
Y232023D01*
X373124Y231305D01*
X372110D01*
X371392Y232023D01*
Y232406D01*
X370674Y233124D01*
X369660D01*
X368942Y232406D01*
Y232023D01*
X368224Y231305D01*
X367210D01*
X366492Y232023D01*
Y232406D01*
X365774Y233124D01*
X364760D01*
X364042Y232406D01*
Y232023D01*
X363324Y231305D01*
X348647D01*
X315616Y264336D01*
X308684D01*
X304879Y268141D01*
X302259D01*
X301050Y269350D01*
X287943D01*
X281176Y276117D01*
X279541D01*
X277944Y277714D01*
Y278363D01*
G01X428748Y275222D02*
X428750D01*
X429140Y274832D01*
Y265609D01*
X428075Y264544D01*
X427052D01*
X425758Y263250D01*
Y260441D01*
X416020Y250703D01*
Y238171D01*
X411377Y233528D01*
X410361D01*
X409644Y234245D01*
Y235261D01*
X412109Y237726D01*
Y238742D01*
X411392Y239459D01*
X410376D01*
X406178Y235261D01*
Y234245D01*
X408628Y231795D01*
Y230779D01*
X407393Y229544D01*
X348065D01*
X314993Y262616D01*
X307970D01*
X304140Y266446D01*
X301359D01*
X299350Y268455D01*
X287635D01*
X281269Y274821D01*
X278466D01*
X274944Y278343D01*
Y278363D01*
G01X279386Y280407D02*
X280193D01*
X281233Y279367D01*
X282713D01*
X283939Y278141D01*
X286391D01*
X293341Y271191D01*
X307673D01*
X310244Y268620D01*
X316012D01*
X349775Y234857D01*
X358970D01*
X359620Y235507D01*
Y235514D01*
X362647Y238541D01*
X364262D01*
X364980Y237823D01*
Y237187D01*
X365698Y236469D01*
X366712D01*
X367430Y237187D01*
Y237823D01*
X368148Y238541D01*
X369162D01*
X369880Y237823D01*
Y237187D01*
X370598Y236469D01*
X371612D01*
X372330Y237187D01*
Y237823D01*
X373048Y238541D01*
X374062D01*
X374780Y237823D01*
Y237187D01*
X375498Y236469D01*
X376512D01*
X377230Y237187D01*
Y237823D01*
X377948Y238541D01*
X378962D01*
X379680Y237823D01*
Y237187D01*
X380398Y236469D01*
X381412D01*
X382130Y237187D01*
Y237823D01*
X382848Y238541D01*
X389843D01*
X398159Y246857D01*
Y247873D01*
X397442Y248590D01*
X396426D01*
X389817Y241981D01*
X388803D01*
X388085Y242700D01*
Y243715D01*
X396711Y252341D01*
X398258D01*
G01X276386Y280407D02*
X278011Y282032D01*
X281458D01*
X282193Y282767D01*
X283569D01*
X294136Y272200D01*
X309263D01*
X310714Y270749D01*
X316219D01*
X350454Y236514D01*
X358280D01*
X361960Y240194D01*
X385902D01*
X386620Y240912D01*
Y241926D01*
X385902Y242644D01*
X368448D01*
X367730Y243362D01*
Y244376D01*
X368448Y245094D01*
X387121D01*
X396828Y254801D01*
X400808D01*
X404738Y258731D01*
Y260421D01*
G01X281767Y277742D02*
Y277715D01*
X289167Y270315D01*
X301960D01*
X302509Y269766D01*
X306652D01*
X310164Y266254D01*
X316040D01*
X349087Y233207D01*
X359740D01*
X361345Y234812D01*
X395396D01*
X396826Y236242D01*
X397842D01*
X398126Y235958D01*
X399142D01*
X399859Y236675D01*
Y237691D01*
X399575Y237975D01*
Y238991D01*
X400292Y239708D01*
X401308D01*
X401592Y239424D01*
X402608D01*
X403325Y240141D01*
Y241157D01*
X403041Y241441D01*
Y242457D01*
X406795Y246211D01*
Y247225D01*
X406076Y247943D01*
X405061D01*
X394203Y237085D01*
X393187D01*
X392470Y237802D01*
Y238818D01*
X402288Y248636D01*
Y252591D01*
X402948Y253251D01*
G01X278918Y286887D02*
X284767D01*
X285458Y287578D01*
X286806D01*
X287757Y286627D01*
Y283524D01*
X292725Y278556D01*
X298470D01*
X299873Y277153D01*
X310976D01*
X310983Y277146D01*
X317246D01*
X337360Y257032D01*
X358431D01*
X360502Y254961D01*
X387449D01*
X389570Y257082D01*
Y259259D01*
X393502Y263191D01*
X406341D01*
X407340Y262192D01*
Y258728D01*
X407777Y258291D01*
X413627D01*
X414345Y259009D01*
Y260023D01*
X413627Y260741D01*
X410818D01*
X410100Y261459D01*
Y262473D01*
X410818Y263191D01*
X414345D01*
X418720Y267566D01*
Y268423D01*
X419613Y269316D01*
X424083D01*
X424788Y270021D01*
X426658D01*
X427258Y270621D01*
Y273001D01*
X426018Y274241D01*
Y277101D01*
X427198Y278281D01*
X429021D01*
X430078Y279338D01*
Y283251D01*
X429428Y283901D01*
Y284951D01*
X430078Y285601D01*
Y289181D01*
X429709Y289550D01*
Y289551D01*
X429519Y289741D01*
X427978D01*
X427138Y288901D01*
Y287530D01*
X427909Y286759D01*
G01X281818Y290787D02*
X287957D01*
X291988Y286756D01*
Y285397D01*
X293677Y283708D01*
X298264D01*
X298855Y284299D01*
X302384D01*
X306154Y280529D01*
X318565D01*
X333857Y265237D01*
X361419D01*
X362137Y264519D01*
Y263505D01*
X361419Y262787D01*
X338738D01*
X338020Y262069D01*
Y261055D01*
X338738Y260337D01*
X362137D01*
X363572Y261772D01*
X365905D01*
X366623Y262490D01*
Y265094D01*
X367341Y265812D01*
X368355D01*
X369073Y265094D01*
Y262490D01*
X369791Y261772D01*
X370805D01*
X371523Y262490D01*
Y265094D01*
X372241Y265812D01*
X373255D01*
X373973Y265094D01*
Y262490D01*
X374691Y261772D01*
X375705D01*
X376423Y262490D01*
Y265094D01*
X377141Y265812D01*
X378155D01*
X378873Y265094D01*
Y262490D01*
X379591Y261772D01*
X380605D01*
X381323Y262490D01*
Y265094D01*
X382041Y265812D01*
X383055D01*
X383773Y265094D01*
Y262490D01*
X384491Y261772D01*
X387394D01*
X392122Y266500D01*
X400767D01*
X401618Y267351D01*
G01X427468Y292287D02*
X426164D01*
X425428Y291551D01*
Y285801D01*
X425728Y285501D01*
Y283411D01*
X424348Y282031D01*
Y277041D01*
X423268Y275961D01*
X421539D01*
X420880Y275302D01*
Y274370D01*
X421539Y273711D01*
X423158D01*
X423768Y273101D01*
Y271871D01*
X422874Y270977D01*
X418926D01*
X412790Y264841D01*
X392804D01*
X384582Y256619D01*
X381440D01*
X380722Y257337D01*
Y259402D01*
X380004Y260120D01*
X378990D01*
X378272Y259402D01*
Y257337D01*
X377554Y256619D01*
X376540D01*
X375822Y257337D01*
Y259402D01*
X375104Y260120D01*
X374090D01*
X373372Y259402D01*
Y257337D01*
X372654Y256619D01*
X371640D01*
X370922Y257337D01*
Y259402D01*
X370204Y260120D01*
X369190D01*
X368472Y259402D01*
Y257337D01*
X367754Y256619D01*
X366740D01*
X366022Y257337D01*
Y259402D01*
X365304Y260120D01*
X364290D01*
X363572Y259402D01*
Y257337D01*
X362854Y256619D01*
X361189D01*
X359124Y258684D01*
X338049D01*
X317914Y278819D01*
X304532D01*
X302383Y280968D01*
X300849D01*
X299401Y282414D01*
X291732D01*
X288738Y285408D01*
Y286849D01*
X286425Y289162D01*
X278402D01*
X276444Y287204D01*
Y286183D01*
G01X281859Y310862D02*
X283288D01*
X287798Y306352D01*
X297527D01*
X301932Y301947D01*
X305193D01*
X306619Y300521D01*
X324217D01*
X329212Y295526D01*
X336170D01*
X337598Y296954D01*
X345278D01*
X351520Y290712D01*
X361995D01*
X369832Y298549D01*
X374543D01*
X383140Y307146D01*
X394227D01*
X401074Y300299D01*
X413832D01*
X417226Y296905D01*
X426280D01*
X431728Y291457D01*
Y254099D01*
X427645Y250016D01*
X426992D01*
G01X278067Y325842D02*
Y326002D01*
X280426Y328361D01*
X282438D01*
X286130Y332053D01*
X287916D01*
X293840Y337977D01*
X299447D01*
X309280Y347810D01*
Y355450D01*
X316967Y363137D01*
X326098D01*
X330107Y367146D01*
Y411229D01*
X322370Y418966D01*
Y421294D01*
X314060Y429604D01*
Y435930D01*
X313530Y436460D01*
G01X282167Y324242D02*
X285212Y327287D01*
X289596D01*
X290910Y325973D01*
X304524D01*
X306030Y327479D01*
Y336513D01*
X306613Y337096D01*
X306690D01*
Y337097D01*
X306760Y337167D01*
Y337246D01*
X311550Y342036D01*
Y354962D01*
X317566Y360978D01*
X324541D01*
X324551Y360988D01*
X325071D01*
X325081Y360978D01*
X335056D01*
X335057Y360977D01*
X335060D01*
X339048Y356989D01*
X343880D01*
G01X286071Y329184D02*
X292568D01*
X302430Y339046D01*
X305880D01*
G01X335610Y658177D02*
Y656059D01*
X333462Y653911D01*
X329553D01*
X327030Y656434D01*
Y656860D01*
X312330Y671560D01*
Y676717D01*
X308133Y680914D01*
X305150D01*
X299341Y686723D01*
X296287D01*
X281030Y701980D01*
Y717020D01*
X275909Y722141D01*
X275880D01*
G01X285880Y722268D02*
X286477Y717895D01*
X289885Y703148D01*
X292471Y697632D01*
X304717Y685386D01*
X306355D01*
X314342Y677399D01*
X314340D01*
X320454Y667199D01*
X327263Y660390D01*
X331079Y658206D01*
X332747Y655636D01*
G01X301795Y310398D02*
X305997Y306196D01*
X334776D01*
X338540Y302432D01*
X346818D01*
X353574Y295676D01*
X355585D01*
X357130Y297221D01*
Y303889D01*
X365344Y312103D01*
X396766D01*
X403594Y305275D01*
X424912D01*
X437423Y292764D01*
Y256507D01*
X441580Y252350D01*
Y250730D01*
G01X305250Y310342D02*
X305734Y309858D01*
X325610D01*
X326873Y311121D01*
X332999D01*
X339438Y304682D01*
X344445D01*
X351174Y311411D01*
X358927D01*
X361269Y313753D01*
X397453D01*
X404275Y306931D01*
X425590D01*
X439073Y293448D01*
Y257976D01*
X444005Y253044D01*
Y249725D01*
X435483Y241203D01*
X424961D01*
G01X403628Y292201D02*
X401123Y289696D01*
X397479D01*
X395610Y291565D01*
Y298377D01*
X393228Y300759D01*
X381431D01*
X375914Y295242D01*
X371197D01*
X363362Y287407D01*
X349479D01*
X348107Y288779D01*
X338612D01*
X337761Y287928D01*
X333827D01*
X330992Y290763D01*
Y290764D01*
X327709Y294046D01*
X322988Y298767D01*
X306840D01*
X305511Y300096D01*
X300979D01*
X300201Y300874D01*
G01X303197Y304297D02*
X304295D01*
X306361Y302231D01*
X325354D01*
X325749Y301839D01*
X330410Y297178D01*
X335485D01*
X336916Y298609D01*
X345966D01*
X352210Y292365D01*
X357186D01*
X361000Y296179D01*
Y303089D01*
X366708Y308797D01*
X394921D01*
X401764Y301954D01*
X414512D01*
X417906Y298560D01*
X426959D01*
X434118Y291401D01*
Y253421D01*
X428318Y247621D01*
X427398D01*
X427258Y247481D01*
X420692D01*
X418905Y245694D01*
G01X304410Y572782D02*
X306180Y571012D01*
Y505011D01*
X308853Y502338D01*
Y474788D01*
X307670Y473605D01*
G01X530779Y637354D02*
X525323Y642810D01*
X512938D01*
X507665Y637537D01*
X496698D01*
X491808Y632647D01*
X474670D01*
X472865Y634452D01*
Y636939D01*
X469944Y639860D01*
X468510D01*
X468342Y639692D01*
X461409D01*
X454201Y646900D01*
X442051D01*
X438230Y650721D01*
X429114D01*
X428350Y649957D01*
X414248D01*
X411929Y647638D01*
X410200D01*
X408683Y649155D01*
X388168D01*
X383885Y644872D01*
X378741D01*
X377250Y643381D01*
X370841D01*
X367900Y640440D01*
X340281D01*
X335470Y635629D01*
X322586D01*
X317873Y640342D01*
X314220D01*
X314005Y640557D01*
X305972D01*
X304796Y639381D01*
X303110D01*
G01X490120Y662703D02*
X475354D01*
X460626Y677431D01*
X434240D01*
X430960Y674151D01*
X423587D01*
X422937Y673501D01*
X413648D01*
X412770Y674379D01*
X382962D01*
X374991Y666408D01*
X367380D01*
X366935Y666853D01*
X359146D01*
X357146Y668853D01*
X353000D01*
X352440Y668293D01*
X351160D01*
X335200Y652333D01*
X328886D01*
X328260Y651707D01*
X326820D01*
X317721Y660806D01*
X315105D01*
X311030Y664881D01*
X304795D01*
X301285Y668391D01*
X294120D01*
G01X332190Y659883D02*
Y661371D01*
X330924Y664637D01*
X329206Y667978D01*
X328215Y668969D01*
X326334Y670163D01*
X314494Y681087D01*
X306393Y689188D01*
X305027D01*
X300392Y691570D01*
X294043Y697919D01*
X291561Y702951D01*
Y704225D01*
X293043Y711807D01*
Y714280D01*
X291570Y718158D01*
Y719758D01*
X293480Y725080D01*
G01X313230Y702465D02*
X308826D01*
X304265Y697904D01*
Y696474D01*
X305610Y695129D01*
X316880D01*
X331645Y680364D01*
X353106D01*
X354761Y678709D01*
X365040D01*
X365700Y679369D01*
X373614D01*
X379443Y685198D01*
X395749D01*
X398975Y688424D01*
X408741D01*
X410069Y689752D01*
X416811D01*
X424861Y681702D01*
X425140D01*
X425408Y681434D01*
X431350D01*
X437027Y687111D01*
X452707D01*
X458687Y693091D01*
X487192D01*
X490385Y689898D01*
X495891D01*
X499996Y694003D01*
X527434D01*
X531599Y689838D01*
G01X293286Y703504D02*
X293457D01*
X303482Y693479D01*
X307895D01*
X315469Y685905D01*
X322971Y678404D01*
X329500D01*
X334618Y673286D01*
X362530D01*
X364442Y675198D01*
X368178D01*
X370381Y677401D01*
X380182D01*
X381322Y678541D01*
X400203D01*
X406583Y684921D01*
X412965D01*
X417834Y680052D01*
X424450D01*
X426842Y677660D01*
X429911D01*
X430140Y677431D01*
X431580D01*
X436319Y682170D01*
X450107D01*
X455655Y687718D01*
X486638D01*
X488574Y685782D01*
X495146D01*
X498990Y689626D01*
X528311D01*
X530486Y687451D01*
Y684649D01*
X528640Y682803D01*
Y670904D01*
X527800Y670064D01*
Y667005D01*
X543771Y651034D01*
X552618D01*
X558011Y645641D01*
X568167D01*
X570520Y643288D01*
X580363D01*
X615050Y608601D01*
Y585103D01*
X619000Y581153D01*
Y548122D01*
X631418Y535704D01*
X645150D01*
G01X307204Y304212D02*
X307380Y304036D01*
X333476D01*
X337016Y300496D01*
X346417D01*
X352897Y294016D01*
X356495D01*
X358890Y296411D01*
Y303315D01*
X366028Y310453D01*
X396076D01*
X402904Y303625D01*
X424228D01*
X435773Y292080D01*
Y252562D01*
X428405Y245194D01*
G01X343880Y356989D02*
Y370862D01*
X332060Y382682D01*
Y414830D01*
X319226Y427664D01*
X318763D01*
X316969Y429458D01*
Y437075D01*
X315940Y438104D01*
G01X310453Y642451D02*
X312884D01*
X314225Y643792D01*
X316403D01*
X323516Y636679D01*
X331545D01*
X336918Y642052D01*
X342350D01*
X344308Y644010D01*
X350560D01*
X352170Y642400D01*
X368004D01*
X370035Y644431D01*
X376804D01*
X378787Y646414D01*
X383933D01*
X387724Y650205D01*
X403490D01*
X404373Y651088D01*
X411640D01*
X411721Y651007D01*
X422730D01*
X423494Y651771D01*
X438829D01*
X442300Y648300D01*
X452709D01*
X455772Y651363D01*
X467993D01*
X468810Y652180D01*
G01X305990Y697189D02*
X306800Y696379D01*
X336197D01*
X339030Y693546D01*
X340470D01*
X343777Y696853D01*
X362440D01*
X363445Y695848D01*
X369109D01*
X375220Y689737D01*
Y689271D01*
X376231Y688260D01*
X386096D01*
X389285Y691449D01*
X390720D01*
X391097Y691071D01*
X398265D01*
X399110Y691916D01*
X409599D01*
X410315Y691200D01*
X417132D01*
X421469Y686863D01*
X428080D01*
X430098Y688881D01*
X433350D01*
X435698Y691229D01*
X444919D01*
X451781Y698091D01*
X490190D01*
X490900Y697381D01*
X496567D01*
X498544Y695404D01*
X528473D01*
X533521Y690356D01*
Y682042D01*
X531545Y680066D01*
Y672020D01*
X533360Y670205D01*
Y667826D01*
X540728Y660458D01*
X547824D01*
X557710Y650572D01*
Y650057D01*
X558725Y649042D01*
X572365D01*
X574880Y646527D01*
X585828D01*
X588665Y643690D01*
X610800D01*
X613484Y641006D01*
X616491D01*
X619795Y637702D01*
X623697D01*
X625710Y635689D01*
X665750D01*
X675753Y625686D01*
X693721D01*
X738700Y580707D01*
Y562302D01*
X742355Y558647D01*
Y493763D01*
X741054Y492462D01*
Y475399D01*
X743126Y473327D01*
Y385957D01*
X702729Y345560D01*
X638105D01*
X637122Y346543D01*
X586664D01*
X534820Y294699D01*
Y291674D01*
X525520Y282374D01*
Y277766D01*
X510435Y262681D01*
Y215523D01*
X517293Y208665D01*
Y194866D01*
X521300Y190859D01*
Y178217D01*
X521326Y178191D01*
X521330D01*
Y178184D01*
X521320D01*
G01X398038Y292571D02*
X398030D01*
Y300411D01*
X394541Y303900D01*
X382230D01*
X375226Y296896D01*
X370517D01*
X362682Y289061D01*
X350832D01*
X345568Y294325D01*
X340242D01*
X336495Y290578D01*
Y290569D01*
G01X399880Y319568D02*
X399248D01*
X397934Y320882D01*
X355207D01*
X349260Y314935D01*
X335819D01*
X335173Y315581D01*
X333540D01*
G01D02*
Y315590D01*
G01X322599Y432505D02*
Y432249D01*
X328232Y426616D01*
X331218D01*
X334380Y423454D01*
Y385652D01*
X343913Y376119D01*
X348758D01*
X349110Y375767D01*
G01X334640Y725035D02*
X340464Y719211D01*
X353449D01*
X354645Y720407D01*
X358545D01*
X361556Y717396D01*
X370527D01*
X370790Y717133D01*
X373283D01*
X374137Y716279D01*
X413744D01*
X417619Y720154D01*
X427655D01*
X428520Y719289D01*
X432145D01*
X432341Y719485D01*
X442650D01*
G01X353060Y61504D02*
X356831Y65275D01*
X360293D01*
X361927Y66433D01*
X387416Y78881D01*
X406014D01*
X426570Y99437D01*
Y192889D01*
X455875Y222194D01*
Y254249D01*
X454805Y255319D01*
Y262448D01*
X457540Y265183D01*
Y298869D01*
X423534Y332875D01*
X409987D01*
X379720Y363142D01*
Y372257D01*
G01X345270Y452745D02*
Y439955D01*
X338470Y433155D01*
Y383896D01*
X343922Y378444D01*
X350000D01*
X352420Y376024D01*
Y375672D01*
G01X343770Y382166D02*
X340160Y385776D01*
Y430169D01*
X347695Y437704D01*
Y465587D01*
X346750Y466532D01*
G01X354690Y377000D02*
X346846Y384844D01*
Y398099D01*
X341830Y403115D01*
Y426940D01*
X349345Y434455D01*
Y470630D01*
X340339Y479636D01*
X338762D01*
G01X364645Y377065D02*
X348970Y392740D01*
Y398309D01*
X343480Y403799D01*
Y426256D01*
X350995Y433771D01*
Y471352D01*
X339506Y482841D01*
G01X348220Y486484D02*
X352645Y472865D01*
Y433080D01*
X345137Y425572D01*
Y404831D01*
X351560Y398408D01*
Y398377D01*
X355921Y391550D01*
X355941D01*
X361199Y386292D01*
X364880Y384455D01*
G01X543280Y491040D02*
X543253D01*
X539329Y494964D01*
X532555D01*
X525809Y488218D01*
X507575D01*
X501050Y494743D01*
Y506629D01*
X467170Y540509D01*
Y542944D01*
X464450Y545664D01*
Y561878D01*
X455264Y571064D01*
X376380D01*
X347247Y541931D01*
X340330D01*
G01X342190Y565848D02*
Y565890D01*
X348400Y572100D01*
X373952D01*
X373966Y572114D01*
X455699D01*
X465620Y562193D01*
Y546454D01*
X468681Y543393D01*
Y540483D01*
X502490Y506674D01*
Y494788D01*
X508010Y489268D01*
X525374D01*
X532120Y496014D01*
X540953D01*
X545891Y491076D01*
X545900D01*
X546250Y490726D01*
Y490302D01*
G01X464050Y633877D02*
X459951D01*
X453279Y640549D01*
X441320D01*
X440235Y639464D01*
X429706D01*
X429446Y639724D01*
X426948Y642221D01*
X422300D01*
X421418Y643103D01*
X406526D01*
X402974Y646655D01*
X393734D01*
X389071Y641992D01*
X382319D01*
X380980Y640653D01*
X375053D01*
X370645Y636245D01*
X351482D01*
X350620Y635383D01*
X343011D01*
X340340Y638054D01*
G01X345580Y638109D02*
X346856Y636833D01*
X350010D01*
X350872Y637695D01*
X370035D01*
X374671Y642331D01*
X380597D01*
X381708Y643442D01*
X383949D01*
X388612Y648105D01*
X404191D01*
X407731Y644565D01*
X422014D01*
X422908Y643671D01*
X431209D01*
X433966Y640914D01*
X439620D01*
X440705Y641999D01*
X455380D01*
X460022Y637357D01*
X466753D01*
X472513Y631597D01*
X492258D01*
X497148Y636487D01*
X510044D01*
X510280Y636723D01*
X520215D01*
X521323Y635615D01*
X543400D01*
G01X429820Y656709D02*
X427975D01*
X426076Y658608D01*
X421310D01*
X419812Y657110D01*
X398417D01*
X397660Y656353D01*
X394046D01*
X390240Y652547D01*
X384240D01*
X380207Y648514D01*
X378770D01*
X378353Y648931D01*
X370278D01*
X368684Y647337D01*
X353607D01*
X351738Y649206D01*
X351730D01*
G01X591279Y656223D02*
X590289Y655233D01*
X584730D01*
X578058Y661905D01*
X571806D01*
X571540Y661639D01*
X563219D01*
X561482Y663376D01*
X554499D01*
X545330Y672545D01*
Y688267D01*
X530655Y702942D01*
X442574D01*
X441405Y704111D01*
X439975D01*
X433295Y697431D01*
X427895D01*
X426633Y698693D01*
X414090D01*
X413833Y698436D01*
X392661D01*
X392630Y698467D01*
X389451D01*
X383503Y692519D01*
X375011D01*
X367900Y699630D01*
X365987D01*
X365560Y700057D01*
X363297D01*
X362501Y700853D01*
X345382D01*
X339800Y695271D01*
X339750D01*
G01X339010Y700406D02*
Y701950D01*
X341627Y704567D01*
X357427D01*
X359695Y706835D01*
X364453D01*
X365902Y708284D01*
X369630D01*
X373584Y704330D01*
X382290D01*
X385642Y707682D01*
X392460D01*
X394403Y705739D01*
X415411D01*
X417594Y707922D01*
X418393D01*
X420145Y709674D01*
X429777D01*
X430020Y709431D01*
X445145D01*
X446516Y708060D01*
X474564D01*
X482405Y715901D01*
X489280D01*
X492552Y719173D01*
X511248D01*
X511303Y719118D01*
X527489D01*
X533388Y713219D01*
X538062D01*
X548812Y702469D01*
X550497D01*
X553405Y699561D01*
Y676619D01*
X554683Y675341D01*
X556817D01*
X564399Y667759D01*
X569438D01*
X571172Y666025D01*
X578196D01*
X578974Y666803D01*
X593625D01*
X597300Y663128D01*
G01X596998Y658008D02*
X596292D01*
X588747Y665553D01*
X579819D01*
X579041Y664775D01*
X569906D01*
X568258Y666423D01*
X563238D01*
X558706Y670955D01*
X555069D01*
X549020Y677004D01*
Y692050D01*
X530727Y710343D01*
X526008D01*
X524522Y708857D01*
X489719D01*
X487537Y706675D01*
X436873D01*
X435086Y704888D01*
X425301D01*
X424032Y703619D01*
X415895D01*
X415560Y703954D01*
X383846D01*
X382972Y703080D01*
X373064D01*
X369110Y707034D01*
X366429D01*
X364980Y705585D01*
X360218D01*
X357950Y703317D01*
X356416D01*
X355202Y702103D01*
X343277D01*
X338926Y697752D01*
G01X352010Y713968D02*
X353928Y715886D01*
X370010D01*
X370510Y715386D01*
X372127D01*
X373460Y714053D01*
X389025D01*
X393580Y709498D01*
Y709056D01*
X395435Y707201D01*
X411847D01*
X413835Y709189D01*
X415265D01*
X415282Y709172D01*
X417867D01*
X420241Y711546D01*
X427684D01*
X430460Y714322D01*
X444129D01*
X446180Y716373D01*
X460788D01*
X468170Y723755D01*
Y724094D01*
X474321Y730245D01*
X486490D01*
X489870Y733625D01*
Y736761D01*
X491967Y738858D01*
X590044D01*
X591515Y737387D01*
X593719D01*
X594729Y736377D01*
Y734947D01*
X601563Y728113D01*
X634948D01*
X636170Y729335D01*
G01X379560Y374955D02*
X379833Y374682D01*
X380725D01*
X382150Y373257D01*
Y363263D01*
X408971Y336442D01*
X422301D01*
X459190Y299553D01*
Y262803D01*
X459370Y262623D01*
Y262609D01*
X459600Y262379D01*
Y262373D01*
X460833Y261140D01*
Y249213D01*
X458265Y246645D01*
Y222242D01*
X428228Y192205D01*
Y98433D01*
X405812Y76017D01*
X393515D01*
X390827Y73329D01*
X383270D01*
X371931Y67981D01*
X368407Y64457D01*
X365670D01*
Y64458D01*
G01X365850Y414874D02*
Y411066D01*
X373549Y403367D01*
Y398941D01*
X375150Y397340D01*
Y339889D01*
X390560Y324479D01*
X390564D01*
X391049Y323994D01*
X398609D01*
X407504Y315099D01*
X409857D01*
X411240Y316482D01*
G01X367520Y701710D02*
X373724D01*
X375991Y699443D01*
X382929D01*
X383203Y699717D01*
X394665D01*
X394696Y699686D01*
X410582D01*
X413600Y702704D01*
X415040D01*
X415375Y702369D01*
X425141D01*
X425670Y702898D01*
X427110D01*
X428577Y701431D01*
X434144D01*
X438074Y705361D01*
X480106D01*
X481275Y704192D01*
X532150D01*
X546580Y689762D01*
Y673063D01*
X552364Y667279D01*
X559493D01*
X563883Y662889D01*
X570226D01*
X570492Y663155D01*
X578576D01*
X581218Y660513D01*
X590895D01*
X591840Y659568D01*
G01X379300Y380862D02*
X379877D01*
X385450Y375289D01*
Y365061D01*
X385630Y364881D01*
Y364841D01*
X410729Y339742D01*
X424883D01*
X425849Y338776D01*
X425850D01*
Y338775D01*
X462490Y302135D01*
Y264171D01*
X462670Y263991D01*
Y263984D01*
X464133Y262521D01*
Y223442D01*
X431528Y190837D01*
Y85646D01*
X412835Y66953D01*
X391684D01*
X388872Y64141D01*
X383247D01*
G01X379286Y378015D02*
X379921Y377380D01*
X380565D01*
X383800Y374145D01*
Y363947D01*
X409655Y338092D01*
X422985D01*
X460840Y300237D01*
Y263487D01*
X461020Y263307D01*
Y263300D01*
X461260Y263060D01*
Y263053D01*
X462483Y261830D01*
Y224126D01*
X429878Y191521D01*
Y86894D01*
X413975Y70991D01*
X402677D01*
X401976Y71692D01*
X396930D01*
X394366Y69128D01*
X383043D01*
X377888Y63973D01*
X373560D01*
G01X371260Y412879D02*
Y408415D01*
X375500Y404175D01*
Y399750D01*
X377100Y398150D01*
Y340701D01*
X391371Y326430D01*
X399409D01*
X408790Y317049D01*
G01X382620Y391882D02*
X380465Y389727D01*
Y386973D01*
X389160Y378278D01*
Y366022D01*
X412140Y343042D01*
X426303D01*
X466470Y302875D01*
Y265734D01*
X467433Y264771D01*
Y221559D01*
X450650Y204776D01*
Y203785D01*
G01X389690Y60665D02*
X390460Y61435D01*
X395768Y63374D01*
X407220D01*
X414347Y65497D01*
X436190Y87340D01*
Y192650D01*
X465783Y222243D01*
Y263212D01*
X464140Y264855D01*
Y302864D01*
X425612Y341392D01*
X411456D01*
X387100Y365748D01*
Y377069D01*
X380882Y383287D01*
X380428D01*
X379750Y383965D01*
G01X401310Y61439D02*
X412623D01*
X437840Y86656D01*
Y188738D01*
X449785Y200683D01*
X449988D01*
X454070Y204765D01*
Y205862D01*
X469083Y220875D01*
Y265455D01*
X468120Y266418D01*
Y303559D01*
X426987Y344692D01*
X412837D01*
X390810Y366719D01*
Y378962D01*
X382190Y387582D01*
Y388077D01*
G01X442380Y75513D02*
X443370Y76503D01*
Y112334D01*
X446553Y115517D01*
Y128781D01*
X441750Y133584D01*
Y187132D01*
X451400Y196782D01*
X451603D01*
X473550Y218729D01*
Y305271D01*
X432479Y346342D01*
X413521D01*
X392460Y367403D01*
Y379889D01*
X385440Y386909D01*
Y397861D01*
X376600Y406701D01*
Y408045D01*
G01X383750Y437058D02*
Y410715D01*
X389740Y404725D01*
G01X378910Y430874D02*
X376435Y433349D01*
Y460306D01*
X373460Y463281D01*
Y464710D01*
X375559Y466809D01*
Y474098D01*
X376240Y474779D01*
Y498085D01*
X376540Y498385D01*
G01X470090Y332824D02*
Y339991D01*
X441760Y368321D01*
Y379443D01*
X420314Y400889D01*
X398197D01*
X385720Y413366D01*
Y438062D01*
X383099Y440683D01*
Y491056D01*
X388982Y496939D01*
G01X376770Y734898D02*
X376547D01*
X370385Y728736D01*
Y719593D01*
X371395Y718583D01*
X398106D01*
X398960Y717729D01*
X410775D01*
X412080Y719034D01*
G01X414080Y721334D02*
X411310D01*
X408755Y718779D01*
X399402D01*
X397873Y720308D01*
X372110D01*
G01X464810Y311253D02*
X470070Y305993D01*
Y267226D01*
X471033Y266263D01*
Y220067D01*
X456020Y205054D01*
Y203957D01*
X450795Y198732D01*
X450592D01*
X439793Y187933D01*
Y85851D01*
X413431Y59489D01*
X392660D01*
X392250Y59899D01*
G01X393370Y411618D02*
X393025Y411273D01*
Y408986D01*
X393020Y408981D01*
Y407551D01*
X394030Y406541D01*
X394041D01*
X398548Y402034D01*
X421610D01*
X444600Y379044D01*
Y369603D01*
X475190Y339013D01*
G01X480830Y333921D02*
Y336667D01*
X445660Y371837D01*
Y379470D01*
X422046Y403084D01*
X400183D01*
X395740Y407527D01*
Y407528D01*
G01X583930Y652439D02*
Y652536D01*
X580283Y656183D01*
X578642D01*
X577506Y657319D01*
X561774D01*
X557319Y661774D01*
X554050D01*
X543370Y672454D01*
Y688176D01*
X530054Y701492D01*
X442241D01*
X434180Y693431D01*
X430090D01*
X429862Y693659D01*
X426275D01*
X424894Y692278D01*
X420091D01*
X417372Y694997D01*
X400131D01*
X397930Y692796D01*
X392080D01*
G01X765250Y357789D02*
X765000Y358039D01*
Y358000D01*
X763500Y359500D01*
Y459000D01*
X765000Y460500D01*
Y552000D01*
X763500Y553500D01*
Y608599D01*
X720731Y651368D01*
X677932D01*
X671300Y658000D01*
X668300D01*
X663600Y662700D01*
Y665700D01*
X658900Y670400D01*
Y684000D01*
X654500Y688400D01*
Y695900D01*
X658900Y700300D01*
Y713247D01*
X656633Y715514D01*
X652431D01*
X636885Y731060D01*
X635450D01*
X635359Y730969D01*
X603712D01*
X599710Y734971D01*
Y735351D01*
X594753Y740308D01*
X478254D01*
X474390Y736444D01*
Y734451D01*
X466129Y726190D01*
X465725D01*
X464715Y725180D01*
Y723560D01*
X458978Y717823D01*
X445570D01*
X443519Y715772D01*
X429850D01*
X427846Y713768D01*
X400992D01*
X396150Y708926D01*
G01X765610Y361194D02*
Y366110D01*
X766500Y367000D01*
Y553644D01*
X764890Y555254D01*
Y608694D01*
X721166Y652418D01*
X678882D01*
X671550Y659750D01*
X668650D01*
X665100Y663300D01*
Y666200D01*
X660400Y670900D01*
Y717228D01*
X645518Y732110D01*
X635010D01*
X634919Y732019D01*
X607144D01*
X603170Y735993D01*
Y736391D01*
X598203Y741358D01*
X474000D01*
X469215Y736573D01*
Y731165D01*
X463660Y725610D01*
Y723990D01*
X458822Y719152D01*
X444762D01*
X442432Y716822D01*
X429412D01*
X427408Y714818D01*
X398221D01*
X394840Y711437D01*
G01X446260Y722014D02*
X441987D01*
X427150Y736851D01*
X424696D01*
X423900Y736055D01*
G01X487832Y624429D02*
X486156Y626105D01*
X473037D01*
X470097Y629045D01*
X445604D01*
G01X458120Y44721D02*
Y44727D01*
X460370Y46977D01*
X468574D01*
X472150Y50553D01*
X489885D01*
X511401Y72069D01*
X513120D01*
G01X553725Y717251D02*
X552373Y718603D01*
X548138D01*
X547807Y718934D01*
X544380D01*
X543125Y720189D01*
Y722551D01*
X534734Y730942D01*
X499668D01*
X497721Y728995D01*
X480195D01*
X473260Y722060D01*
Y719499D01*
X471246Y717485D01*
X465687D01*
X460822Y712620D01*
G01X451820Y712210D02*
X454720Y709310D01*
X473556D01*
X481411Y717165D01*
X488731D01*
X491989Y720423D01*
X511768D01*
X511823Y720368D01*
X530386D01*
X532767Y717987D01*
X535197D01*
X540500Y712684D01*
X543736D01*
X546861Y709559D01*
X550004D01*
G01X555062Y708679D02*
X552476Y711265D01*
X551728D01*
X549390Y713603D01*
X546066D01*
X545735Y713934D01*
X541018D01*
X534594Y720358D01*
X533142D01*
X530114Y723386D01*
Y724820D01*
X528992Y725942D01*
X504890D01*
X502257Y723309D01*
X485787D01*
X473248Y710770D01*
X457526D01*
X454070Y714226D01*
G01X465913Y402659D02*
Y402665D01*
X466643Y403395D01*
X503715D01*
X519730Y419410D01*
Y434515D01*
X523667Y438452D01*
G01X465883Y399834D02*
Y399833D01*
X466413Y399303D01*
X502381D01*
X521680Y418602D01*
Y431275D01*
X522379Y431974D01*
G01X477710Y722299D02*
X481347Y725936D01*
X501330D01*
X503836Y728442D01*
X531706D01*
X537626Y722522D01*
Y721402D01*
X542594Y716434D01*
X546771D01*
X547102Y716103D01*
X550616D01*
X552867Y713852D01*
X554867D01*
X556735Y711984D01*
X561070D01*
X562540Y713454D01*
G01X466620Y714137D02*
X468280Y715797D01*
X471326D01*
X474900Y719371D01*
Y721929D01*
X480157Y727186D01*
X500810D01*
X503316Y729692D01*
X534216D01*
X541729Y722179D01*
Y719817D01*
X543862Y717684D01*
X547289D01*
X547620Y717353D01*
X551181D01*
X553328Y715206D01*
X555991D01*
X557488Y713709D01*
G01X473940Y714184D02*
X484315Y724559D01*
X501730D01*
X504363Y727192D01*
X531188D01*
X536229Y722151D01*
Y720594D01*
X541639Y715184D01*
X546253D01*
X546584Y714853D01*
X550087D01*
X552391Y712549D01*
X554317D01*
X558187Y708679D01*
X560062D01*
G01X482500Y184169D02*
X482990Y184659D01*
Y243364D01*
X487920Y248294D01*
Y249759D01*
X519270Y281109D01*
Y287989D01*
X601348Y370067D01*
Y407563D01*
X604505Y410720D01*
Y425942D01*
X614785Y436222D01*
X626097D01*
X641125Y451250D01*
Y515007D01*
X640117Y516015D01*
Y517445D01*
X640470Y517798D01*
Y523266D01*
G01X487080Y180918D02*
X484645Y183353D01*
Y242242D01*
X489310Y246907D01*
Y249664D01*
X520320Y280674D01*
Y287554D01*
X602398Y369632D01*
Y406509D01*
X605555Y409666D01*
Y425507D01*
X615220Y435172D01*
X626532D01*
X642900Y451540D01*
Y513898D01*
X644368Y515366D01*
Y523772D01*
X645040Y524444D01*
G01X480220Y185766D02*
X481880Y187426D01*
Y244193D01*
X486670Y248983D01*
Y250008D01*
X518220Y281558D01*
Y288424D01*
X600298Y370502D01*
Y407999D01*
X603455Y411156D01*
Y426377D01*
X614941Y437863D01*
X626253D01*
X640075Y451685D01*
Y514572D01*
X639067Y515580D01*
Y517028D01*
X634530Y521565D01*
G01X480310Y642224D02*
X482942D01*
X489422Y648704D01*
X494720D01*
X496941Y650925D01*
Y655367D01*
X513401Y671827D01*
X517572D01*
X520107Y674362D01*
Y683962D01*
X518947Y685122D01*
G01X493020Y646701D02*
X496481D01*
X502474Y652694D01*
X506405D01*
X507415Y653704D01*
Y657227D01*
X522170Y671982D01*
Y681111D01*
X527111Y686052D01*
G01X520370Y625158D02*
X520740D01*
X523428Y627846D01*
X539072D01*
X546069Y620849D01*
X568380D01*
X580400Y608829D01*
Y601379D01*
X591860Y589919D01*
Y571619D01*
X593150Y570329D01*
Y568270D01*
X594320Y567100D01*
Y549184D01*
X614812Y528692D01*
X622475D01*
X624567Y526600D01*
X645324D01*
X646765Y525159D01*
Y515712D01*
X644350Y513297D01*
Y450939D01*
X627133Y433722D01*
X615821D01*
X607310Y425211D01*
Y409340D01*
X603848Y405878D01*
Y369031D01*
X531070Y296253D01*
Y293228D01*
X521770Y283928D01*
Y280070D01*
X502435Y260735D01*
Y205084D01*
X507305Y200214D01*
Y160444D01*
X509710Y158039D01*
Y127269D01*
G01X515600Y172800D02*
X518500Y175700D01*
Y183500D01*
X511500Y190500D01*
Y193700D01*
X509100Y196100D01*
Y201700D01*
X504000Y206800D01*
Y226918D01*
X504941Y227859D01*
G01X506234Y207368D02*
X507100Y208234D01*
Y229500D01*
X504800Y231800D01*
Y252900D01*
X506800Y254900D01*
Y263332D01*
X523020Y279552D01*
Y283410D01*
X532320Y292710D01*
Y295735D01*
X585628Y349043D01*
X638170D01*
X639153Y348060D01*
X701693D01*
X738035Y384402D01*
Y456698D01*
X735625Y459108D01*
Y490578D01*
X739855Y494808D01*
Y556148D01*
X736201Y559802D01*
X736200D01*
Y579671D01*
X692685Y623186D01*
X674333D01*
X664369Y633150D01*
X632433D01*
X629881Y630598D01*
X618256D01*
X617973Y630315D01*
X615490D01*
X609867Y635938D01*
X594647D01*
X585511Y645074D01*
X571070D01*
X568639Y647505D01*
X558494D01*
X556460Y649539D01*
Y650054D01*
X548465Y658049D01*
X541369D01*
X532100Y667318D01*
Y669214D01*
X530295Y671019D01*
Y681468D01*
X532271Y683444D01*
Y689166D01*
X531599Y689838D01*
G01X514766Y208222D02*
Y208457D01*
X509185Y214038D01*
Y263208D01*
X524270Y278293D01*
Y282892D01*
X533570Y292192D01*
Y295217D01*
X586146Y347793D01*
X637650D01*
X638633Y346810D01*
X702211D01*
X739285Y383884D01*
Y492470D01*
X741105Y494290D01*
Y557398D01*
X737451Y561052D01*
X737450D01*
Y580189D01*
X693203Y624436D01*
X675230D01*
X665266Y634400D01*
X631222D01*
X628831Y632009D01*
X617894D01*
X617450Y631565D01*
X616010D01*
X609912Y637663D01*
X604850D01*
X600980Y641533D01*
G01X622100Y465822D02*
Y485328D01*
X618370Y489058D01*
Y505078D01*
X579503Y543945D01*
Y557077D01*
X579248Y557332D01*
Y565956D01*
X576763Y568440D01*
X575753Y569450D01*
X575373D01*
X572600Y572223D01*
Y593118D01*
X556298Y609420D01*
X520946D01*
X514890Y615476D01*
X507916D01*
X506967Y616425D01*
X504980D01*
G01X625900Y461769D02*
X625225Y462444D01*
Y501065D01*
X620474Y505816D01*
Y505945D01*
X595026Y531393D01*
X583288Y543132D01*
Y549535D01*
X585263Y551510D01*
Y552940D01*
X582688Y555515D01*
Y569467D01*
X583748Y570527D01*
Y571957D01*
X581340Y574365D01*
Y588447D01*
X557915Y611872D01*
X527876D01*
X522636Y617112D01*
X509091D01*
X508400Y617803D01*
G01X640470Y523266D02*
X635274D01*
X635250Y523290D01*
X613723D01*
X591811Y545202D01*
Y556587D01*
X589150Y559248D01*
Y588084D01*
X577900Y599334D01*
Y606300D01*
X565852Y618348D01*
X539239D01*
X532241Y625346D01*
X525585D01*
X522622Y622383D01*
X515296D01*
X504430Y633249D01*
X501120D01*
G01X634530Y521565D02*
X613963D01*
X590761Y544767D01*
Y550424D01*
X586815Y554370D01*
Y561673D01*
X588094Y562952D01*
Y587454D01*
X576850Y598698D01*
Y605865D01*
X565417Y617298D01*
X538794D01*
X535005Y621087D01*
X514149D01*
X508892Y626344D01*
X505585D01*
X498340Y633589D01*
X496690D01*
G01X533270Y679351D02*
X534700Y677921D01*
Y668254D01*
X541246Y661708D01*
X548516D01*
X553985Y656239D01*
X556896D01*
X562610Y650525D01*
X572652D01*
X575400Y647777D01*
X586348D01*
X588910Y645215D01*
X611996D01*
X613864Y643347D01*
X615294D01*
X617120Y645173D01*
X666107D01*
X673275Y638005D01*
X687219D01*
X750448Y574776D01*
Y504000D01*
X750500D01*
X751000Y503500D01*
Y483000D01*
X750448Y482448D01*
Y387975D01*
X703042Y340569D01*
X644410D01*
X641970Y338129D01*
X639930D01*
X638049Y340010D01*
X585435D01*
X538570Y293145D01*
Y285144D01*
X521700Y268274D01*
Y209878D01*
X525525Y206053D01*
Y196017D01*
X524718Y195210D01*
Y192280D01*
X525293Y191705D01*
G01X623290Y641222D02*
X666777D01*
X679197Y628802D01*
X694150D01*
X741550Y581402D01*
Y565850D01*
X746339Y561061D01*
Y495661D01*
X748000Y494000D01*
Y487000D01*
X746339Y485339D01*
Y385634D01*
X702548Y341843D01*
X585500D01*
X537320Y293663D01*
Y290638D01*
X528020Y281338D01*
Y276730D01*
X513950Y262660D01*
Y223204D01*
X519119Y218035D01*
Y208091D01*
X520068Y207142D01*
G01X620510Y639427D02*
X620789Y639148D01*
X624046D01*
X626160Y637034D01*
X666495D01*
X676592Y626937D01*
X694247D01*
X739959Y581225D01*
Y562821D01*
X745089Y557691D01*
Y494589D01*
X743500Y493000D01*
Y490500D01*
X745089Y488911D01*
Y386152D01*
X702030Y343093D01*
X584982D01*
X536070Y294181D01*
Y291156D01*
X526770Y281856D01*
Y277248D01*
X512700Y263178D01*
Y219187D01*
X516551Y215336D01*
Y214987D01*
G01X531597Y697509D02*
Y697309D01*
X536000Y692906D01*
Y668722D01*
X541764Y662958D01*
X549041D01*
X554510Y657489D01*
X557420D01*
X563134Y651775D01*
X573176D01*
X575924Y649027D01*
X586868D01*
X587550Y648345D01*
X603804D01*
X604353Y648894D01*
X611166D01*
X613080Y646980D01*
X616888D01*
X617160Y646708D01*
X666647D01*
X674100Y639255D01*
X715031D01*
X750000Y604286D01*
Y582337D01*
X751698Y580639D01*
Y505802D01*
X752500Y505000D01*
Y481500D01*
X751698Y480698D01*
Y387457D01*
X701854Y337613D01*
X692320D01*
X691590Y336883D01*
Y336879D01*
X639410D01*
X637578Y338711D01*
X612925D01*
X610774Y336560D01*
X601626D01*
X601520Y336666D01*
X583859D01*
X539820Y292627D01*
Y284622D01*
X528174Y272976D01*
Y269104D01*
X522950Y263880D01*
Y213986D01*
X524405Y212531D01*
G01X523800Y611145D02*
X527117D01*
X527547Y610715D01*
X557587D01*
X580290Y588012D01*
Y571973D01*
X580298Y571965D01*
Y557767D01*
X580553Y557512D01*
Y544381D01*
X619420Y505514D01*
Y489493D01*
X623825Y485088D01*
Y448232D01*
X602405Y426812D01*
Y411591D01*
X599248Y408434D01*
Y374203D01*
X579788Y354743D01*
G01X510700Y634300D02*
Y632388D01*
X519655Y623433D01*
X522177D01*
X525140Y626396D01*
X538256D01*
X545254Y619398D01*
X566287D01*
X578950Y606735D01*
Y600195D01*
X590410Y588735D01*
Y566128D01*
X592870Y563668D01*
Y545628D01*
X613348Y525150D01*
X644334D01*
X645040Y524444D01*
G01X683112Y479786D02*
X684802Y481476D01*
Y489916D01*
X661658Y513060D01*
Y518257D01*
X646673Y533242D01*
X631546D01*
X613996Y550792D01*
Y578666D01*
X610545Y582117D01*
Y593179D01*
X613245Y595879D01*
Y597309D01*
X610480Y600074D01*
Y610837D01*
X579679Y641638D01*
X569830D01*
X567474Y643991D01*
X557320D01*
X551927Y649384D01*
X539095D01*
X524705Y663774D01*
Y681203D01*
X528836Y685334D01*
Y686767D01*
X527702Y687901D01*
X517888D01*
G01X596470Y655231D02*
X598398Y653303D01*
X645607D01*
X645950Y652959D01*
X649186D01*
X651199Y650946D01*
X668830D01*
X676571Y643205D01*
X715460D01*
Y643206D01*
X716672D01*
X756160Y603718D01*
Y508840D01*
X757000Y508000D01*
Y478000D01*
X755650Y476650D01*
Y385822D01*
X703491Y333663D01*
X695183D01*
X694081Y332561D01*
X600025D01*
X599870Y332716D01*
X585496D01*
X551820Y299040D01*
Y288657D01*
X534995Y271832D01*
Y252858D01*
X532483Y250346D01*
Y226367D01*
X534700Y224150D01*
Y198300D01*
X536000Y197000D01*
Y195000D01*
X534045Y193045D01*
Y188549D01*
X536370Y186224D01*
Y153700D01*
X538655Y151415D01*
G01X541657Y207645D02*
Y257932D01*
X537142Y262447D01*
Y271509D01*
X553270Y287637D01*
Y298439D01*
X586097Y331266D01*
X599260D01*
X599415Y331111D01*
X700152D01*
X701050Y330213D01*
X703860D01*
X762000Y388353D01*
Y462000D01*
X763500Y463500D01*
Y550000D01*
X762000Y551500D01*
Y605164D01*
X717821Y649343D01*
X677804D01*
X671050Y656097D01*
X667715D01*
X654529Y669283D01*
Y679671D01*
X652700Y681500D01*
Y700900D01*
X657335Y705535D01*
Y707024D01*
X656325Y708034D01*
X646491D01*
X629028Y725497D01*
X589025D01*
X576914Y737608D01*
X563753D01*
X562713Y736568D01*
Y734367D01*
X553193Y724847D01*
G01X532320Y209470D02*
Y218261D01*
X526380Y224201D01*
Y232671D01*
X526640Y232931D01*
Y265452D01*
X529839Y268651D01*
Y272729D01*
X541070Y283960D01*
Y292109D01*
X584377Y335416D01*
X601000D01*
X601155Y335261D01*
X692228D01*
X693330Y336363D01*
X702372D01*
X752950Y386941D01*
Y479450D01*
X754000Y480500D01*
Y506500D01*
X753455Y507045D01*
Y602599D01*
X715549Y640505D01*
X675451D01*
X667998Y647958D01*
X619128D01*
X616656Y650430D01*
X598940D01*
X598920Y650410D01*
X589290D01*
X588950Y650070D01*
G01X528105Y230594D02*
Y249471D01*
X531820Y253186D01*
Y272210D01*
X542320Y282710D01*
Y291591D01*
X584895Y334166D01*
X600474D01*
X600629Y334011D01*
X693480D01*
X694582Y335113D01*
X702890D01*
X754200Y386423D01*
Y478200D01*
X755500Y479500D01*
Y507121D01*
X754705Y507916D01*
Y603117D01*
X716067Y641755D01*
X675969D01*
X668228Y649496D01*
X650598D01*
X648585Y651509D01*
X617351D01*
X617180Y651680D01*
X598420D01*
X598400Y651660D01*
X594010D01*
X593875Y651795D01*
X587663D01*
X586145Y650277D01*
X576447D01*
X571335Y655389D01*
X561497D01*
X557330Y659556D01*
X554213D01*
X549086Y664683D01*
X542479D01*
X539830Y667332D01*
G01X636010Y469995D02*
X634160Y471845D01*
Y499198D01*
X598975Y534383D01*
X595845D01*
X586738Y543490D01*
Y552962D01*
X585765Y553935D01*
Y562108D01*
X586138Y562481D01*
Y571054D01*
X582970Y574222D01*
Y588302D01*
X555519Y615753D01*
X532689D01*
X532420Y615484D01*
G01X530779Y637354D02*
X545918D01*
X547972Y635300D01*
X555475D01*
X555710Y635065D01*
X560482D01*
X564841Y630706D01*
X571985D01*
X586300Y616391D01*
Y609794D01*
X591052Y605042D01*
X593445D01*
X596650Y601837D01*
Y599594D01*
X600730Y595514D01*
Y570536D01*
X602768Y568498D01*
Y567064D01*
X601662Y565958D01*
Y551743D01*
X615200Y538205D01*
Y538186D01*
X616320Y537066D01*
G01X557222Y285109D02*
Y300340D01*
X586423Y329541D01*
X598551D01*
G01X565168Y694614D02*
X563337Y696445D01*
Y711806D01*
X564265Y712734D01*
Y714169D01*
X562131Y716303D01*
X557149D01*
X553399Y720053D01*
X549945D01*
X546566Y723432D01*
Y724119D01*
G01X563577Y692284D02*
X565278D01*
X566893Y693899D01*
Y700336D01*
X566490Y700739D01*
Y707664D01*
X566787Y707961D01*
Y712587D01*
X565320Y714054D01*
Y715755D01*
X561259Y719816D01*
X555422D01*
X553335Y721903D01*
X550535D01*
G01X557426Y724436D02*
X560996Y720866D01*
X561694D01*
X566370Y716190D01*
Y715025D01*
X569940Y711455D01*
Y694386D01*
X565168Y689614D01*
G01X560865Y285434D02*
Y287093D01*
X560860D01*
X559270Y288683D01*
Y299705D01*
X586479Y326914D01*
X601050D01*
X601450Y326514D01*
Y326509D01*
G01X664450Y435739D02*
Y461070D01*
X662803Y462717D01*
Y470263D01*
X669724Y477184D01*
Y478800D01*
X668582Y479942D01*
X662105D01*
X648425Y493622D01*
Y502804D01*
X649681Y504060D01*
Y506360D01*
X648215Y507826D01*
Y525760D01*
X645925Y528050D01*
X625168D01*
X623076Y530142D01*
X615413D01*
X597775Y547780D01*
Y558283D01*
X596240Y559818D01*
Y569290D01*
X593310Y572220D01*
Y590520D01*
X581850Y601980D01*
Y610508D01*
X572530Y619828D01*
Y625118D01*
X571650Y625998D01*
G01X585693Y722428D02*
Y721942D01*
X582376Y718625D01*
Y688068D01*
X582980Y687464D01*
Y679440D01*
X577800Y674260D01*
X565522D01*
X565168Y674614D01*
G01Y669614D02*
X568510Y672956D01*
X578264D01*
X584230Y678922D01*
Y687987D01*
X583675Y688542D01*
Y698009D01*
X593650Y707984D01*
Y715617D01*
X597265Y719232D01*
X598880D01*
G01X576519Y687665D02*
X572339Y691845D01*
Y713952D01*
X564704Y721587D01*
X564319D01*
G01X578030Y690236D02*
X573590Y694676D01*
Y714470D01*
X571685Y716375D01*
Y729136D01*
X566798Y734023D01*
G01X687130Y464132D02*
Y465503D01*
X681420Y471213D01*
Y471698D01*
X661981Y491137D01*
X659803D01*
X658790Y492150D01*
Y492472D01*
X650731Y500531D01*
Y506795D01*
X649265Y508261D01*
Y526195D01*
X646360Y529100D01*
X625603D01*
X623511Y531192D01*
X615848D01*
X598825Y548215D01*
Y558724D01*
X597290Y560259D01*
Y569725D01*
X594360Y572655D01*
Y590961D01*
X583755Y601566D01*
Y610854D01*
X577000Y617609D01*
Y620029D01*
G01X574730Y625521D02*
X584810Y615441D01*
Y609799D01*
X590617Y603992D01*
X593010D01*
X595600Y601402D01*
Y598935D01*
X599310Y595225D01*
Y559724D01*
X599875Y559159D01*
Y548650D01*
X616283Y532242D01*
X625333D01*
X627425Y530150D01*
X646795D01*
X650960Y525985D01*
Y511512D01*
X651245Y511226D01*
X657230Y505241D01*
Y500152D01*
X683416Y473966D01*
X708618D01*
X710671Y471913D01*
G01X576846Y675985D02*
X581705Y680844D01*
Y683860D01*
X581126Y684439D01*
Y719143D01*
X583440Y721457D01*
Y724927D01*
G01X577570Y734118D02*
X577440D01*
Y734156D01*
X576215Y732931D01*
Y723407D01*
X576720Y722902D01*
Y707654D01*
X579755Y704619D01*
Y688461D01*
X577010Y685716D01*
Y682718D01*
G01X585400Y697289D02*
X603222D01*
X605394Y699461D01*
X607170D01*
X607380Y699671D01*
G01X683112Y464038D02*
Y461255D01*
X685903Y458464D01*
Y444046D01*
X673871Y432014D01*
X640765D01*
X638089Y429338D01*
X633144D01*
X617280Y413474D01*
Y378265D01*
X600770Y361755D01*
Y358702D01*
G01X594860Y395088D02*
X597810Y398038D01*
Y409910D01*
X600680Y412780D01*
G01X598670Y508170D02*
X600680Y506160D01*
Y412780D01*
G01X616730Y633290D02*
X610618Y639402D01*
X607040D01*
X605010Y641432D01*
Y641435D01*
G01X639940Y687841D02*
X635679Y692102D01*
X619765D01*
X618694Y693173D01*
X601858D01*
X601410Y693621D01*
X592575D01*
X589500Y690546D01*
G01X604220Y703774D02*
Y713172D01*
X601813Y715579D01*
G01X655610Y706309D02*
X651716D01*
X647202Y701795D01*
X595894D01*
X594398Y703291D01*
X592960D01*
G01X611050Y423087D02*
X618351Y430388D01*
X634080D01*
X636756Y433064D01*
X673436D01*
X684853Y444481D01*
Y456254D01*
X679175Y461932D01*
Y464038D01*
G01X611130Y417928D02*
X609325Y419733D01*
Y423802D01*
X617482Y431959D01*
X627424D01*
X645800Y450335D01*
Y460331D01*
X648325Y462856D01*
Y464286D01*
X647231Y465380D01*
Y472648D01*
X649646Y475063D01*
Y476493D01*
X648106Y478033D01*
Y492449D01*
X647375Y493180D01*
Y503239D01*
X648631Y504495D01*
Y505925D01*
X646460Y508096D01*
Y512967D01*
G01X622510Y635544D02*
X622235Y635819D01*
X619307D01*
X617186Y637940D01*
X614496D01*
X610834Y641603D01*
X608310D01*
G01X635840Y449890D02*
X638350Y452400D01*
Y507893D01*
G01X630570Y451450D02*
X631460Y452340D01*
Y465449D01*
X632680Y466669D01*
G01X631930Y655254D02*
X644619D01*
X645865Y656500D01*
X648419D01*
X652023Y652896D01*
X669722D01*
X676759Y645859D01*
X716777D01*
X758500Y604136D01*
Y546000D01*
X759500Y545000D01*
Y472000D01*
X758500Y471000D01*
Y469500D01*
G01X641690Y443656D02*
X646525D01*
X656080Y453211D01*
Y468994D01*
X660264Y473178D01*
X662960D01*
X667774Y477992D01*
G01X639940Y687841D02*
X643379D01*
X652450Y678770D01*
Y669594D01*
X667197Y654847D01*
X670529D01*
X677283Y648093D01*
X717303D01*
X760500Y604896D01*
Y547500D01*
X761500Y546500D01*
Y469000D01*
X760500Y468000D01*
Y388621D01*
X703817Y331938D01*
X701770D01*
G01X652690Y531693D02*
X653950D01*
X656210Y529433D01*
Y529426D01*
X670300Y515336D01*
Y514148D01*
X679927Y504521D01*
X680790D01*
G01X745220Y327250D02*
Y337120D01*
X756700Y348600D01*
X758501D01*
X769700Y359799D01*
Y572800D01*
X767000Y575500D01*
Y609400D01*
X734000Y642400D01*
X733600D01*
X721600Y654400D01*
X679500D01*
X672400Y661500D01*
X669300D01*
X666800Y664000D01*
Y668200D01*
X662400Y672600D01*
Y683800D01*
X665000Y686400D01*
Y689900D01*
X662400Y692500D01*
Y718254D01*
X659200Y721454D01*
G01X747600Y323527D02*
Y337100D01*
X756500Y346000D01*
X759500D01*
X774500Y361000D01*
Y606979D01*
X725410Y656069D01*
X681331D01*
X675505Y661895D01*
X675405D01*
X674000Y663300D01*
X670600D01*
X668900Y665000D01*
Y671700D01*
X670300Y673100D01*
Y688500D01*
X665800Y693000D01*
Y720443D01*
X658860Y727383D01*
G01X657570Y730414D02*
X658269D01*
X667500Y721183D01*
Y693900D01*
X672400Y689000D01*
Y682667D01*
X683460Y671607D01*
Y665391D01*
X691132Y657719D01*
X726094D01*
X776200Y607613D01*
Y359800D01*
X759000Y342600D01*
X755500D01*
X750700Y337800D01*
Y323771D01*
G01X656000Y732400D02*
X658617D01*
X670000Y721017D01*
Y718900D01*
X672100Y716800D01*
Y694100D01*
X674550Y691650D01*
Y682851D01*
X685110Y672291D01*
Y666075D01*
X691816Y659369D01*
X729440D01*
X734265Y654544D01*
Y651893D01*
X777900Y608258D01*
Y358900D01*
X759700Y340700D01*
X755969D01*
X753125Y337856D01*
Y331199D01*
X753230Y331094D01*
Y328262D01*
G01X679590Y352829D02*
X681356Y351063D01*
X701160D01*
X717451Y367354D01*
Y426239D01*
X702730Y440960D01*
Y455483D01*
G01X679430Y350013D02*
X701595D01*
X733295Y381713D01*
Y477526D01*
X730763Y480058D01*
X719058D01*
X718397Y479397D01*
X714077D01*
X711998Y481476D01*
X709129D01*
X707439Y479786D01*
X706734D01*
G01X731340Y476723D02*
X720970D01*
X720855Y476608D01*
X712579D01*
X711352Y477835D01*
X682305D01*
X681162Y478978D01*
Y482033D01*
X682852Y483723D01*
X683112D01*
G01X759400Y334839D02*
X762139D01*
X783000Y355700D01*
Y613693D01*
X729200Y667493D01*
Y710500D01*
X692300Y747400D01*
X677000D01*
X675100Y749300D01*
G01X672710Y746235D02*
X674145Y744800D01*
X691600D01*
X727200Y709200D01*
Y667159D01*
X781300Y613059D01*
Y356500D01*
X761800Y337000D01*
X758600D01*
X756655Y335055D01*
X754850D01*
G01X672500Y749179D02*
Y749100D01*
X670985Y747585D01*
Y745515D01*
X674350Y742150D01*
X688650D01*
X725100Y705700D01*
Y666500D01*
X730319Y661281D01*
Y661181D01*
X735920Y655580D01*
Y652573D01*
X779600Y608893D01*
Y357700D01*
X760800Y338900D01*
X758000D01*
X756891Y337791D01*
X755500D01*
G01X738130Y502748D02*
X737698Y502316D01*
X697102D01*
X692520Y506898D01*
G01X732817Y489435D02*
X708271D01*
X702585Y483749D01*
G54D17*
G01X130797Y83291D02*
X146226Y67862D01*
X206707D01*
X218416Y56153D01*
X242680D01*
G01X745614Y312688D02*
X733742Y324560D01*
X664612D01*
X655122Y315070D01*
G54D27*
G01X188899Y240208D02*
X187599Y238908D01*
X186877D01*
X185970Y238001D01*
Y229338D01*
X184658Y228026D01*
X180256D01*
X178364Y226134D01*
X175875D01*
X175625Y226384D01*
X175573D01*
G01Y225084D02*
X175675D01*
X175925Y225334D01*
X178696D01*
X180588Y227226D01*
X184990D01*
X186770Y229006D01*
Y237669D01*
X187209Y238108D01*
X187599D01*
X188899Y236808D01*
G01X209540Y223796D02*
Y223898D01*
X209290Y224148D01*
Y227009D01*
X208350Y227949D01*
Y237294D01*
X209741Y238685D01*
X210635D01*
X211935Y237385D01*
G01X208240Y223796D02*
Y223898D01*
X208490Y224148D01*
Y226677D01*
X207550Y227617D01*
Y237626D01*
X209409Y239485D01*
X210635D01*
X211935Y240785D01*
G01X243862Y257931D02*
Y257983D01*
X244112Y258233D01*
Y261751D01*
X243666Y262197D01*
X241613D01*
G01X245162Y257931D02*
Y258033D01*
X244912Y258283D01*
Y261638D01*
X245413Y262139D01*
X247389D01*
G01X241613Y268197D02*
X243938D01*
X244304Y267831D01*
Y266429D01*
X245398Y265335D01*
X251023D01*
X251720Y264638D01*
Y263405D01*
X251470Y263155D01*
Y263053D01*
G01X247389Y268139D02*
X245542D01*
X245104Y267701D01*
Y266761D01*
X245730Y266135D01*
X251355D01*
X252520Y264970D01*
Y263405D01*
X252770Y263155D01*
Y263053D01*
G01X281945Y260231D02*
Y261012D01*
X282225Y261292D01*
X283042D01*
X283879Y260455D01*
Y256680D01*
X289930Y250629D01*
Y247379D01*
X292269Y245040D01*
Y244686D01*
X292341Y244614D01*
G01X282166Y262922D02*
Y262453D01*
X282527Y262092D01*
X283374D01*
X284679Y260787D01*
Y257012D01*
X290730Y250961D01*
Y247711D01*
X292835Y245606D01*
X293189D01*
X293261Y245534D01*
G54D18*
G01X149721Y292987D02*
X153148Y296414D01*
X166053D01*
X170792Y291675D01*
X174803D01*
X175899Y290579D01*
X178225D01*
G01X699600Y776000D02*
Y760400D01*
X730800Y729200D01*
Y728400D01*
G01X704000Y770800D02*
X728500Y746300D01*
X729500D01*
G54D19*
G01X171154Y715673D02*
X165711Y721116D01*
X135664D01*
X132330Y724450D01*
Y732982D01*
X132334D01*
G01X233793Y257697D02*
Y257499D01*
X232895Y256601D01*
X230811D01*
X228772Y258640D01*
Y262961D01*
X226536Y265197D01*
X226421D01*
G01D02*
X225973D01*
G01X226421D02*
X228983Y267759D01*
X232543D01*
X233605Y266697D01*
X233793D01*
G01X590874Y275195D02*
X586336Y279733D01*
X570468D01*
X568258Y281943D01*
X563183D01*
X562663Y281423D01*
X562638D01*
X559143Y277928D01*
X550093D01*
X539267Y267102D01*
M02*
